FILE_TYPE = MACRO_DRAWING;
SET COLOR_WIRE YELLOW;
SET COLOR_PROP ORANGE;
SET COLOR_DOT WHITE;
SET COLOR_ARC YELLOW;
SET COLOR_BODY GREEN;
SET COLOR_NOTE PURPLE;
SET PROP_DISPLAY VALUE;
SET PAGE_NUMBER P111;
FORCEADD OFFPAGE..2
R 2
(-4075 450);
FORCEPROP 2 LAST $XR0 111 
J 0
(-4330 450);
DISPLAY 0.638298 (-4330 450);
PAINT MONO (-4330 450);
FORCEPROP 2 LAST CDS_LIB standard
J 0
(-4075 450);
PAINT MONO (-4075 450);
DISPLAY INVISIBLE (-4075 450);
FORCEPROP 1 LAST OFFPAGE TRUE
J 2
(-4400 325);
DISPLAY 0.872340 (-4400 325);
DISPLAY INVISIBLE (-4400 325);
FORCEPROP 1 LAST COMMENT_BODY TRUE
J 2
(-4030 355);
DISPLAY 0.872340 (-4030 355);
PAINT GREEN (-4030 355);
DISPLAY INVISIBLE (-4030 355);
FORCEPROP 2 LAST PATH I1
J 0
(-4025 525);
DISPLAY 1.021277 (-4025 525);
DISPLAY INVISIBLE (-4025 525);
FORCEADD OFFPAGE..1
(-4075 2050);
FORCEPROP 2 LAST $XR1 110 
J 0
(-4416 2050);
DISPLAY 0.638298 (-4416 2050);
PAINT MONO (-4416 2050);
FORCEPROP 2 LAST $XR0 57 
J 0
(-4296 2050);
DISPLAY 0.638298 (-4296 2050);
PAINT MONO (-4296 2050);
FORCEPROP 2 LAST CDS_LIB standard
J 0
(-4075 2050);
PAINT MONO (-4075 2050);
DISPLAY INVISIBLE (-4075 2050);
FORCEPROP 1 LAST OFFPAGE TRUE
J 0
(-3750 1925);
DISPLAY 0.872340 (-3750 1925);
DISPLAY INVISIBLE (-3750 1925);
FORCEPROP 1 LAST COMMENT_BODY TRUE
J 0
(-3950 1950);
DISPLAY 0.872340 (-3950 1950);
PAINT GREEN (-3950 1950);
DISPLAY INVISIBLE (-3950 1950);
FORCEPROP 2 LAST PATH I10
J 0
(-4025 2125);
DISPLAY 1.021277 (-4025 2125);
DISPLAY INVISIBLE (-4025 2125);
FORCEADD TAP..1
(-1500 3000);
FORCEPROP 3 LASTPIN (-1550 3000) SIG_NAME M_G_CPU1_SA_DQ<3>
J 0
(-1540 3010);
DISPLAY 0.659574 (-1540 3010);
PAINT MONO (-1540 3010);
DISPLAY INVISIBLE (-1540 3010);
FORCEPROP 1 LASTPIN (-1550 3000) BN 3
J 0
(-1562 3008);
DISPLAY 0.680851 (-1562 3008);
PAINT GREEN (-1562 3008);
FORCEPROP 2 LAST CDS_LIB standard
J 0
(-1500 3000);
PAINT MONO (-1500 3000);
DISPLAY INVISIBLE (-1500 3000);
FORCEPROP 1 LAST BODY_TYPE PLUMBING
J 0
(-1500 3050);
DISPLAY 0.872340 (-1500 3050);
PAINT GREEN (-1500 3050);
DISPLAY INVISIBLE (-1500 3050);
FORCEPROP 1 LAST HDL_TAP TRUE
J 0
(-1175 2875);
DISPLAY 0.872340 (-1175 2875);
DISPLAY INVISIBLE (-1175 2875);
FORCEPROP 1 LAST PATH I100
J 0
(-1502 3000);
DISPLAY 0.872340 (-1502 3000);
PAINT GREEN (-1502 3000);
DISPLAY INVISIBLE (-1502 3000);
FORCEADD OFFPAGE..3
(-675 2775);
FORCEPROP 2 LAST $XR1 110 
J 0
(-371 2775);
DISPLAY 0.638298 (-371 2775);
PAINT MONO (-371 2775);
FORCEPROP 2 LAST $XR0 57 
J 0
(-461 2775);
DISPLAY 0.638298 (-461 2775);
PAINT MONO (-461 2775);
FORCEPROP 2 LAST CDS_LIB standard
J 2
(-675 2775);
DISPLAY INVISIBLE (-675 2775);
FORCEPROP 1 LAST OFFPAGE TRUE
J 0
(-350 2650);
DISPLAY 0.872340 (-350 2650);
DISPLAY INVISIBLE (-350 2650);
FORCEPROP 1 LAST COMMENT_BODY TRUE
J 0
(-725 2675);
DISPLAY 0.872340 (-725 2675);
PAINT GREEN (-725 2675);
DISPLAY INVISIBLE (-725 2675);
FORCEPROP 2 LAST PATH I101
J 0
(-475 2850);
DISPLAY 1.021277 (-475 2850);
DISPLAY INVISIBLE (-475 2850);
FORCEADD TAP..1
(-1500 3250);
FORCEPROP 3 LASTPIN (-1550 3250) SIG_NAME M_G_CPU1_SA_DQ<8>
J 0
(-1540 3260);
DISPLAY 0.659574 (-1540 3260);
PAINT MONO (-1540 3260);
DISPLAY INVISIBLE (-1540 3260);
FORCEPROP 1 LASTPIN (-1550 3250) BN 8
J 0
(-1562 3258);
DISPLAY 0.680851 (-1562 3258);
PAINT GREEN (-1562 3258);
FORCEPROP 2 LAST CDS_LIB standard
J 0
(-1500 3250);
PAINT MONO (-1500 3250);
DISPLAY INVISIBLE (-1500 3250);
FORCEPROP 1 LAST BODY_TYPE PLUMBING
J 0
(-1500 3300);
DISPLAY 0.872340 (-1500 3300);
PAINT GREEN (-1500 3300);
DISPLAY INVISIBLE (-1500 3300);
FORCEPROP 1 LAST HDL_TAP TRUE
J 0
(-1175 3125);
DISPLAY 0.872340 (-1175 3125);
DISPLAY INVISIBLE (-1175 3125);
FORCEPROP 1 LAST PATH I102
J 0
(-1502 3250);
DISPLAY 0.872340 (-1502 3250);
PAINT GREEN (-1502 3250);
DISPLAY INVISIBLE (-1502 3250);
FORCEADD TAP..1
(-1500 3200);
FORCEPROP 3 LASTPIN (-1550 3200) SIG_NAME M_G_CPU1_SA_DQ<7>
J 0
(-1540 3210);
DISPLAY 0.659574 (-1540 3210);
PAINT MONO (-1540 3210);
DISPLAY INVISIBLE (-1540 3210);
FORCEPROP 1 LASTPIN (-1550 3200) BN 7
J 0
(-1562 3208);
DISPLAY 0.680851 (-1562 3208);
PAINT GREEN (-1562 3208);
FORCEPROP 2 LAST CDS_LIB standard
J 0
(-1500 3200);
PAINT MONO (-1500 3200);
DISPLAY INVISIBLE (-1500 3200);
FORCEPROP 1 LAST BODY_TYPE PLUMBING
J 0
(-1500 3250);
DISPLAY 0.872340 (-1500 3250);
PAINT GREEN (-1500 3250);
DISPLAY INVISIBLE (-1500 3250);
FORCEPROP 1 LAST HDL_TAP TRUE
J 0
(-1175 3075);
DISPLAY 0.872340 (-1175 3075);
DISPLAY INVISIBLE (-1175 3075);
FORCEPROP 1 LAST PATH I103
J 0
(-1502 3200);
DISPLAY 0.872340 (-1502 3200);
PAINT GREEN (-1502 3200);
DISPLAY INVISIBLE (-1502 3200);
FORCEADD TAP..1
(-1500 3150);
FORCEPROP 3 LASTPIN (-1550 3150) SIG_NAME M_G_CPU1_SA_DQ<6>
J 0
(-1540 3160);
DISPLAY 0.659574 (-1540 3160);
PAINT MONO (-1540 3160);
DISPLAY INVISIBLE (-1540 3160);
FORCEPROP 1 LASTPIN (-1550 3150) BN 6
J 0
(-1562 3158);
DISPLAY 0.680851 (-1562 3158);
PAINT GREEN (-1562 3158);
FORCEPROP 2 LAST CDS_LIB standard
J 0
(-1500 3150);
PAINT MONO (-1500 3150);
DISPLAY INVISIBLE (-1500 3150);
FORCEPROP 1 LAST BODY_TYPE PLUMBING
J 0
(-1500 3200);
DISPLAY 0.872340 (-1500 3200);
PAINT GREEN (-1500 3200);
DISPLAY INVISIBLE (-1500 3200);
FORCEPROP 1 LAST HDL_TAP TRUE
J 0
(-1175 3025);
DISPLAY 0.872340 (-1175 3025);
DISPLAY INVISIBLE (-1175 3025);
FORCEPROP 1 LAST PATH I104
J 0
(-1502 3150);
DISPLAY 0.872340 (-1502 3150);
PAINT GREEN (-1502 3150);
DISPLAY INVISIBLE (-1502 3150);
FORCEADD TAP..1
(-1500 3350);
FORCEPROP 3 LASTPIN (-1550 3350) SIG_NAME M_G_CPU1_SA_DQ<10>
J 0
(-1540 3360);
DISPLAY 0.659574 (-1540 3360);
PAINT MONO (-1540 3360);
DISPLAY INVISIBLE (-1540 3360);
FORCEPROP 1 LASTPIN (-1550 3350) BN 10
J 0
(-1562 3358);
DISPLAY 0.680851 (-1562 3358);
PAINT GREEN (-1562 3358);
FORCEPROP 2 LAST CDS_LIB standard
J 0
(-1500 3350);
PAINT MONO (-1500 3350);
DISPLAY INVISIBLE (-1500 3350);
FORCEPROP 1 LAST BODY_TYPE PLUMBING
J 0
(-1500 3400);
DISPLAY 0.872340 (-1500 3400);
PAINT GREEN (-1500 3400);
DISPLAY INVISIBLE (-1500 3400);
FORCEPROP 1 LAST HDL_TAP TRUE
J 0
(-1175 3225);
DISPLAY 0.872340 (-1175 3225);
DISPLAY INVISIBLE (-1175 3225);
FORCEPROP 1 LAST PATH I105
J 0
(-1502 3350);
DISPLAY 0.872340 (-1502 3350);
PAINT GREEN (-1502 3350);
DISPLAY INVISIBLE (-1502 3350);
FORCEADD TAP..1
(-1500 3300);
FORCEPROP 3 LASTPIN (-1550 3300) SIG_NAME M_G_CPU1_SA_DQ<9>
J 0
(-1540 3310);
DISPLAY 0.659574 (-1540 3310);
PAINT MONO (-1540 3310);
DISPLAY INVISIBLE (-1540 3310);
FORCEPROP 1 LASTPIN (-1550 3300) BN 9
J 0
(-1562 3308);
DISPLAY 0.680851 (-1562 3308);
PAINT GREEN (-1562 3308);
FORCEPROP 2 LAST CDS_LIB standard
J 0
(-1500 3300);
PAINT MONO (-1500 3300);
DISPLAY INVISIBLE (-1500 3300);
FORCEPROP 1 LAST BODY_TYPE PLUMBING
J 0
(-1500 3350);
DISPLAY 0.872340 (-1500 3350);
PAINT GREEN (-1500 3350);
DISPLAY INVISIBLE (-1500 3350);
FORCEPROP 1 LAST HDL_TAP TRUE
J 0
(-1175 3175);
DISPLAY 0.872340 (-1175 3175);
DISPLAY INVISIBLE (-1175 3175);
FORCEPROP 1 LAST PATH I106
J 0
(-1502 3300);
DISPLAY 0.872340 (-1502 3300);
PAINT GREEN (-1502 3300);
DISPLAY INVISIBLE (-1502 3300);
FORCEADD TAP..1
(-1500 3500);
FORCEPROP 3 LASTPIN (-1550 3500) SIG_NAME M_G_CPU1_SA_DQ<13>
J 0
(-1540 3510);
DISPLAY 0.659574 (-1540 3510);
PAINT MONO (-1540 3510);
DISPLAY INVISIBLE (-1540 3510);
FORCEPROP 1 LASTPIN (-1550 3500) BN 13
J 0
(-1562 3508);
DISPLAY 0.680851 (-1562 3508);
PAINT GREEN (-1562 3508);
FORCEPROP 2 LAST CDS_LIB standard
J 0
(-1500 3500);
PAINT MONO (-1500 3500);
DISPLAY INVISIBLE (-1500 3500);
FORCEPROP 1 LAST BODY_TYPE PLUMBING
J 0
(-1500 3550);
DISPLAY 0.872340 (-1500 3550);
PAINT GREEN (-1500 3550);
DISPLAY INVISIBLE (-1500 3550);
FORCEPROP 1 LAST HDL_TAP TRUE
J 0
(-1175 3375);
DISPLAY 0.872340 (-1175 3375);
DISPLAY INVISIBLE (-1175 3375);
FORCEPROP 1 LAST PATH I107
J 0
(-1502 3500);
DISPLAY 0.872340 (-1502 3500);
PAINT GREEN (-1502 3500);
DISPLAY INVISIBLE (-1502 3500);
FORCEADD TAP..1
(-1500 3450);
FORCEPROP 3 LASTPIN (-1550 3450) SIG_NAME M_G_CPU1_SA_DQ<12>
J 0
(-1540 3460);
DISPLAY 0.659574 (-1540 3460);
PAINT MONO (-1540 3460);
DISPLAY INVISIBLE (-1540 3460);
FORCEPROP 1 LASTPIN (-1550 3450) BN 12
J 0
(-1562 3458);
DISPLAY 0.680851 (-1562 3458);
PAINT GREEN (-1562 3458);
FORCEPROP 2 LAST CDS_LIB standard
J 0
(-1500 3450);
PAINT MONO (-1500 3450);
DISPLAY INVISIBLE (-1500 3450);
FORCEPROP 1 LAST BODY_TYPE PLUMBING
J 0
(-1500 3500);
DISPLAY 0.872340 (-1500 3500);
PAINT GREEN (-1500 3500);
DISPLAY INVISIBLE (-1500 3500);
FORCEPROP 1 LAST HDL_TAP TRUE
J 0
(-1175 3325);
DISPLAY 0.872340 (-1175 3325);
DISPLAY INVISIBLE (-1175 3325);
FORCEPROP 1 LAST PATH I108
J 0
(-1502 3450);
DISPLAY 0.872340 (-1502 3450);
PAINT GREEN (-1502 3450);
DISPLAY INVISIBLE (-1502 3450);
FORCEADD TAP..1
(-1500 3400);
FORCEPROP 3 LASTPIN (-1550 3400) SIG_NAME M_G_CPU1_SA_DQ<11>
J 0
(-1540 3410);
DISPLAY 0.659574 (-1540 3410);
PAINT MONO (-1540 3410);
DISPLAY INVISIBLE (-1540 3410);
FORCEPROP 1 LASTPIN (-1550 3400) BN 11
J 0
(-1562 3408);
DISPLAY 0.680851 (-1562 3408);
PAINT GREEN (-1562 3408);
FORCEPROP 2 LAST CDS_LIB standard
J 0
(-1500 3400);
PAINT MONO (-1500 3400);
DISPLAY INVISIBLE (-1500 3400);
FORCEPROP 1 LAST BODY_TYPE PLUMBING
J 0
(-1500 3450);
DISPLAY 0.872340 (-1500 3450);
PAINT GREEN (-1500 3450);
DISPLAY INVISIBLE (-1500 3450);
FORCEPROP 1 LAST HDL_TAP TRUE
J 0
(-1175 3275);
DISPLAY 0.872340 (-1175 3275);
DISPLAY INVISIBLE (-1175 3275);
FORCEPROP 1 LAST PATH I109
J 0
(-1502 3400);
DISPLAY 0.872340 (-1502 3400);
PAINT GREEN (-1502 3400);
DISPLAY INVISIBLE (-1502 3400);
FORCEADD OFFPAGE..1
(-4075 2175);
FORCEPROP 2 LAST $XR3 113 
J 0
(-4447 2139);
DISPLAY 0.638298 (-4447 2139);
PAINT MONO (-4447 2139);
FORCEPROP 2 LAST $XR2 112 
J 0
(-4327 2139);
DISPLAY 0.638298 (-4327 2139);
PAINT MONO (-4327 2139);
FORCEPROP 2 LAST $XR1 110 
J 0
(-4447 2175);
DISPLAY 0.638298 (-4447 2175);
PAINT MONO (-4447 2175);
FORCEPROP 2 LAST $XR0 130 
J 0
(-4327 2175);
DISPLAY 0.638298 (-4327 2175);
PAINT MONO (-4327 2175);
FORCEPROP 2 LAST CDS_LIB standard
J 0
(-4075 2175);
PAINT MONO (-4075 2175);
DISPLAY INVISIBLE (-4075 2175);
FORCEPROP 1 LAST OFFPAGE TRUE
J 0
(-3750 2050);
DISPLAY 0.872340 (-3750 2050);
DISPLAY INVISIBLE (-3750 2050);
FORCEPROP 1 LAST COMMENT_BODY TRUE
J 0
(-3950 2075);
DISPLAY 0.872340 (-3950 2075);
PAINT GREEN (-3950 2075);
DISPLAY INVISIBLE (-3950 2075);
FORCEPROP 2 LAST PATH I11
J 0
(-4025 2250);
DISPLAY 1.021277 (-4025 2250);
DISPLAY INVISIBLE (-4025 2250);
FORCEADD TAP..1
(-1500 3550);
FORCEPROP 3 LASTPIN (-1550 3550) SIG_NAME M_G_CPU1_SA_DQ<14>
J 0
(-1540 3560);
DISPLAY 0.659574 (-1540 3560);
PAINT MONO (-1540 3560);
DISPLAY INVISIBLE (-1540 3560);
FORCEPROP 1 LASTPIN (-1550 3550) BN 14
J 0
(-1562 3558);
DISPLAY 0.680851 (-1562 3558);
PAINT GREEN (-1562 3558);
FORCEPROP 2 LAST CDS_LIB standard
J 0
(-1500 3550);
PAINT MONO (-1500 3550);
DISPLAY INVISIBLE (-1500 3550);
FORCEPROP 1 LAST BODY_TYPE PLUMBING
J 0
(-1500 3600);
DISPLAY 0.872340 (-1500 3600);
PAINT GREEN (-1500 3600);
DISPLAY INVISIBLE (-1500 3600);
FORCEPROP 1 LAST HDL_TAP TRUE
J 0
(-1175 3425);
DISPLAY 0.872340 (-1175 3425);
DISPLAY INVISIBLE (-1175 3425);
FORCEPROP 1 LAST PATH I110
J 0
(-1502 3550);
DISPLAY 0.872340 (-1502 3550);
PAINT GREEN (-1502 3550);
DISPLAY INVISIBLE (-1502 3550);
FORCEADD TAP..1
(-1500 3600);
FORCEPROP 3 LASTPIN (-1550 3600) SIG_NAME M_G_CPU1_SA_DQ<15>
J 0
(-1540 3610);
DISPLAY 0.659574 (-1540 3610);
PAINT MONO (-1540 3610);
DISPLAY INVISIBLE (-1540 3610);
FORCEPROP 1 LASTPIN (-1550 3600) BN 15
J 0
(-1562 3608);
DISPLAY 0.680851 (-1562 3608);
PAINT GREEN (-1562 3608);
FORCEPROP 2 LAST CDS_LIB standard
J 0
(-1500 3600);
PAINT MONO (-1500 3600);
DISPLAY INVISIBLE (-1500 3600);
FORCEPROP 1 LAST BODY_TYPE PLUMBING
J 0
(-1500 3650);
DISPLAY 0.872340 (-1500 3650);
PAINT GREEN (-1500 3650);
DISPLAY INVISIBLE (-1500 3650);
FORCEPROP 1 LAST HDL_TAP TRUE
J 0
(-1175 3475);
DISPLAY 0.872340 (-1175 3475);
DISPLAY INVISIBLE (-1175 3475);
FORCEPROP 1 LAST PATH I111
J 0
(-1502 3600);
DISPLAY 0.872340 (-1502 3600);
PAINT GREEN (-1502 3600);
DISPLAY INVISIBLE (-1502 3600);
FORCEADD TAP..1
(-1500 3750);
FORCEPROP 3 LASTPIN (-1550 3750) SIG_NAME M_G_CPU1_SA_DQ<18>
J 0
(-1540 3760);
DISPLAY 0.659574 (-1540 3760);
PAINT MONO (-1540 3760);
DISPLAY INVISIBLE (-1540 3760);
FORCEPROP 1 LASTPIN (-1550 3750) BN 18
J 0
(-1562 3758);
DISPLAY 0.680851 (-1562 3758);
PAINT GREEN (-1562 3758);
FORCEPROP 2 LAST CDS_LIB standard
J 0
(-1500 3750);
PAINT MONO (-1500 3750);
DISPLAY INVISIBLE (-1500 3750);
FORCEPROP 1 LAST BODY_TYPE PLUMBING
J 0
(-1500 3800);
DISPLAY 0.872340 (-1500 3800);
PAINT GREEN (-1500 3800);
DISPLAY INVISIBLE (-1500 3800);
FORCEPROP 1 LAST HDL_TAP TRUE
J 0
(-1175 3625);
DISPLAY 0.872340 (-1175 3625);
DISPLAY INVISIBLE (-1175 3625);
FORCEPROP 1 LAST PATH I112
J 0
(-1502 3750);
DISPLAY 0.872340 (-1502 3750);
PAINT GREEN (-1502 3750);
DISPLAY INVISIBLE (-1502 3750);
FORCEADD TAP..1
(-1500 3700);
FORCEPROP 3 LASTPIN (-1550 3700) SIG_NAME M_G_CPU1_SA_DQ<17>
J 0
(-1540 3710);
DISPLAY 0.659574 (-1540 3710);
PAINT MONO (-1540 3710);
DISPLAY INVISIBLE (-1540 3710);
FORCEPROP 1 LASTPIN (-1550 3700) BN 17
J 0
(-1562 3708);
DISPLAY 0.680851 (-1562 3708);
PAINT GREEN (-1562 3708);
FORCEPROP 2 LAST CDS_LIB standard
J 0
(-1500 3700);
PAINT MONO (-1500 3700);
DISPLAY INVISIBLE (-1500 3700);
FORCEPROP 1 LAST BODY_TYPE PLUMBING
J 0
(-1500 3750);
DISPLAY 0.872340 (-1500 3750);
PAINT GREEN (-1500 3750);
DISPLAY INVISIBLE (-1500 3750);
FORCEPROP 1 LAST HDL_TAP TRUE
J 0
(-1175 3575);
DISPLAY 0.872340 (-1175 3575);
DISPLAY INVISIBLE (-1175 3575);
FORCEPROP 1 LAST PATH I113
J 0
(-1502 3700);
DISPLAY 0.872340 (-1502 3700);
PAINT GREEN (-1502 3700);
DISPLAY INVISIBLE (-1502 3700);
FORCEADD TAP..1
(-1500 3650);
FORCEPROP 3 LASTPIN (-1550 3650) SIG_NAME M_G_CPU1_SA_DQ<16>
J 0
(-1540 3660);
DISPLAY 0.659574 (-1540 3660);
PAINT MONO (-1540 3660);
DISPLAY INVISIBLE (-1540 3660);
FORCEPROP 1 LASTPIN (-1550 3650) BN 16
J 0
(-1562 3658);
DISPLAY 0.680851 (-1562 3658);
PAINT GREEN (-1562 3658);
FORCEPROP 2 LAST CDS_LIB standard
J 0
(-1500 3650);
PAINT MONO (-1500 3650);
DISPLAY INVISIBLE (-1500 3650);
FORCEPROP 1 LAST BODY_TYPE PLUMBING
J 0
(-1500 3700);
DISPLAY 0.872340 (-1500 3700);
PAINT GREEN (-1500 3700);
DISPLAY INVISIBLE (-1500 3700);
FORCEPROP 1 LAST HDL_TAP TRUE
J 0
(-1175 3525);
DISPLAY 0.872340 (-1175 3525);
DISPLAY INVISIBLE (-1175 3525);
FORCEPROP 1 LAST PATH I114
J 0
(-1502 3650);
DISPLAY 0.872340 (-1502 3650);
PAINT GREEN (-1502 3650);
DISPLAY INVISIBLE (-1502 3650);
FORCEADD TAP..1
(-1500 3800);
FORCEPROP 3 LASTPIN (-1550 3800) SIG_NAME M_G_CPU1_SA_DQ<19>
J 0
(-1540 3810);
DISPLAY 0.659574 (-1540 3810);
PAINT MONO (-1540 3810);
DISPLAY INVISIBLE (-1540 3810);
FORCEPROP 1 LASTPIN (-1550 3800) BN 19
J 0
(-1562 3808);
DISPLAY 0.680851 (-1562 3808);
PAINT GREEN (-1562 3808);
FORCEPROP 2 LAST CDS_LIB standard
J 0
(-1500 3800);
PAINT MONO (-1500 3800);
DISPLAY INVISIBLE (-1500 3800);
FORCEPROP 1 LAST BODY_TYPE PLUMBING
J 0
(-1500 3850);
DISPLAY 0.872340 (-1500 3850);
PAINT GREEN (-1500 3850);
DISPLAY INVISIBLE (-1500 3850);
FORCEPROP 1 LAST HDL_TAP TRUE
J 0
(-1175 3675);
DISPLAY 0.872340 (-1175 3675);
DISPLAY INVISIBLE (-1175 3675);
FORCEPROP 1 LAST PATH I115
J 0
(-1502 3800);
DISPLAY 0.872340 (-1502 3800);
PAINT GREEN (-1502 3800);
DISPLAY INVISIBLE (-1502 3800);
FORCEADD TAP..1
(-1500 3850);
FORCEPROP 3 LASTPIN (-1550 3850) SIG_NAME M_G_CPU1_SA_DQ<20>
J 0
(-1540 3860);
DISPLAY 0.659574 (-1540 3860);
PAINT MONO (-1540 3860);
DISPLAY INVISIBLE (-1540 3860);
FORCEPROP 1 LASTPIN (-1550 3850) BN 20
J 0
(-1562 3858);
DISPLAY 0.680851 (-1562 3858);
PAINT GREEN (-1562 3858);
FORCEPROP 2 LAST CDS_LIB standard
J 0
(-1500 3850);
PAINT MONO (-1500 3850);
DISPLAY INVISIBLE (-1500 3850);
FORCEPROP 1 LAST BODY_TYPE PLUMBING
J 0
(-1500 3900);
DISPLAY 0.872340 (-1500 3900);
PAINT GREEN (-1500 3900);
DISPLAY INVISIBLE (-1500 3900);
FORCEPROP 1 LAST HDL_TAP TRUE
J 0
(-1175 3725);
DISPLAY 0.872340 (-1175 3725);
DISPLAY INVISIBLE (-1175 3725);
FORCEPROP 1 LAST PATH I116
J 0
(-1502 3850);
DISPLAY 0.872340 (-1502 3850);
PAINT GREEN (-1502 3850);
DISPLAY INVISIBLE (-1502 3850);
FORCEADD TAP..1
(-1500 4000);
FORCEPROP 3 LASTPIN (-1550 4000) SIG_NAME M_G_CPU1_SA_DQ<23>
J 0
(-1540 4010);
DISPLAY 0.659574 (-1540 4010);
PAINT MONO (-1540 4010);
DISPLAY INVISIBLE (-1540 4010);
FORCEPROP 1 LASTPIN (-1550 4000) BN 23
J 0
(-1562 4008);
DISPLAY 0.680851 (-1562 4008);
PAINT GREEN (-1562 4008);
FORCEPROP 2 LAST CDS_LIB standard
J 0
(-1500 4000);
DISPLAY INVISIBLE (-1500 4000);
FORCEPROP 1 LAST BODY_TYPE PLUMBING
J 0
(-1500 4050);
DISPLAY 0.872340 (-1500 4050);
PAINT GREEN (-1500 4050);
DISPLAY INVISIBLE (-1500 4050);
FORCEPROP 1 LAST HDL_TAP TRUE
J 0
(-1175 3875);
DISPLAY 0.872340 (-1175 3875);
DISPLAY INVISIBLE (-1175 3875);
FORCEPROP 1 LAST PATH I117
J 0
(-1502 4000);
DISPLAY 0.872340 (-1502 4000);
PAINT GREEN (-1502 4000);
DISPLAY INVISIBLE (-1502 4000);
FORCEADD TAP..1
(-1500 3950);
FORCEPROP 3 LASTPIN (-1550 3950) SIG_NAME M_G_CPU1_SA_DQ<22>
J 0
(-1540 3960);
DISPLAY 0.659574 (-1540 3960);
PAINT MONO (-1540 3960);
DISPLAY INVISIBLE (-1540 3960);
FORCEPROP 1 LASTPIN (-1550 3950) BN 22
J 0
(-1562 3958);
DISPLAY 0.680851 (-1562 3958);
PAINT GREEN (-1562 3958);
FORCEPROP 2 LAST CDS_LIB standard
J 0
(-1500 3950);
DISPLAY INVISIBLE (-1500 3950);
FORCEPROP 1 LAST BODY_TYPE PLUMBING
J 0
(-1500 4000);
DISPLAY 0.872340 (-1500 4000);
PAINT GREEN (-1500 4000);
DISPLAY INVISIBLE (-1500 4000);
FORCEPROP 1 LAST HDL_TAP TRUE
J 0
(-1175 3825);
DISPLAY 0.872340 (-1175 3825);
DISPLAY INVISIBLE (-1175 3825);
FORCEPROP 1 LAST PATH I118
J 0
(-1502 3950);
DISPLAY 0.872340 (-1502 3950);
PAINT GREEN (-1502 3950);
DISPLAY INVISIBLE (-1502 3950);
FORCEADD TAP..1
(-1500 3900);
FORCEPROP 3 LASTPIN (-1550 3900) SIG_NAME M_G_CPU1_SA_DQ<21>
J 0
(-1540 3910);
DISPLAY 0.659574 (-1540 3910);
PAINT MONO (-1540 3910);
DISPLAY INVISIBLE (-1540 3910);
FORCEPROP 1 LASTPIN (-1550 3900) BN 21
J 0
(-1562 3908);
DISPLAY 0.680851 (-1562 3908);
PAINT GREEN (-1562 3908);
FORCEPROP 2 LAST CDS_LIB standard
J 0
(-1500 3900);
PAINT MONO (-1500 3900);
DISPLAY INVISIBLE (-1500 3900);
FORCEPROP 1 LAST BODY_TYPE PLUMBING
J 0
(-1500 3950);
DISPLAY 0.872340 (-1500 3950);
PAINT GREEN (-1500 3950);
DISPLAY INVISIBLE (-1500 3950);
FORCEPROP 1 LAST HDL_TAP TRUE
J 0
(-1175 3775);
DISPLAY 0.872340 (-1175 3775);
DISPLAY INVISIBLE (-1175 3775);
FORCEPROP 1 LAST PATH I119
J 0
(-1502 3900);
DISPLAY 0.872340 (-1502 3900);
PAINT GREEN (-1502 3900);
DISPLAY INVISIBLE (-1502 3900);
FORCEADD OFFPAGE..3
R 2
(-4075 2575);
FORCEPROP 2 LAST $XR1 110 
J 0
(-4444 2575);
DISPLAY 0.638298 (-4444 2575);
PAINT MONO (-4444 2575);
FORCEPROP 2 LAST $XR0 57 
J 0
(-4324 2575);
DISPLAY 0.638298 (-4324 2575);
PAINT MONO (-4324 2575);
FORCEPROP 2 LAST CDS_LIB standard
J 0
(-4075 2575);
PAINT MONO (-4075 2575);
DISPLAY INVISIBLE (-4075 2575);
FORCEPROP 1 LAST OFFPAGE TRUE
J 2
(-4400 2450);
DISPLAY 0.872340 (-4400 2450);
DISPLAY INVISIBLE (-4400 2450);
FORCEPROP 1 LAST COMMENT_BODY TRUE
J 2
(-4025 2475);
DISPLAY 0.872340 (-4025 2475);
PAINT GREEN (-4025 2475);
DISPLAY INVISIBLE (-4025 2475);
FORCEPROP 2 LAST PATH I12
J 0
(-4025 2650);
DISPLAY 1.021277 (-4025 2650);
DISPLAY INVISIBLE (-4025 2650);
FORCEADD TAP..1
(-1500 4050);
FORCEPROP 3 LASTPIN (-1550 4050) SIG_NAME M_G_CPU1_SA_DQ<24>
J 0
(-1540 4060);
DISPLAY 0.659574 (-1540 4060);
PAINT MONO (-1540 4060);
DISPLAY INVISIBLE (-1540 4060);
FORCEPROP 1 LASTPIN (-1550 4050) BN 24
J 0
(-1562 4058);
DISPLAY 0.680851 (-1562 4058);
PAINT GREEN (-1562 4058);
FORCEPROP 2 LAST CDS_LIB standard
J 0
(-1500 4050);
DISPLAY INVISIBLE (-1500 4050);
FORCEPROP 1 LAST BODY_TYPE PLUMBING
J 0
(-1500 4100);
DISPLAY 0.872340 (-1500 4100);
PAINT GREEN (-1500 4100);
DISPLAY INVISIBLE (-1500 4100);
FORCEPROP 1 LAST HDL_TAP TRUE
J 0
(-1175 3925);
DISPLAY 0.872340 (-1175 3925);
DISPLAY INVISIBLE (-1175 3925);
FORCEPROP 1 LAST PATH I120
J 0
(-1502 4050);
DISPLAY 0.872340 (-1502 4050);
PAINT GREEN (-1502 4050);
DISPLAY INVISIBLE (-1502 4050);
FORCEADD TAP..1
(-1500 4100);
FORCEPROP 3 LASTPIN (-1550 4100) SIG_NAME M_G_CPU1_SA_DQ<25>
J 0
(-1540 4110);
DISPLAY 0.659574 (-1540 4110);
PAINT MONO (-1540 4110);
DISPLAY INVISIBLE (-1540 4110);
FORCEPROP 1 LASTPIN (-1550 4100) BN 25
J 0
(-1562 4108);
DISPLAY 0.680851 (-1562 4108);
PAINT GREEN (-1562 4108);
FORCEPROP 2 LAST CDS_LIB standard
J 0
(-1500 4100);
DISPLAY INVISIBLE (-1500 4100);
FORCEPROP 1 LAST BODY_TYPE PLUMBING
J 0
(-1500 4150);
DISPLAY 0.872340 (-1500 4150);
PAINT GREEN (-1500 4150);
DISPLAY INVISIBLE (-1500 4150);
FORCEPROP 1 LAST HDL_TAP TRUE
J 0
(-1175 3975);
DISPLAY 0.872340 (-1175 3975);
DISPLAY INVISIBLE (-1175 3975);
FORCEPROP 1 LAST PATH I121
J 0
(-1502 4100);
DISPLAY 0.872340 (-1502 4100);
PAINT GREEN (-1502 4100);
DISPLAY INVISIBLE (-1502 4100);
FORCEADD TAP..1
(-1500 4150);
FORCEPROP 3 LASTPIN (-1550 4150) SIG_NAME M_G_CPU1_SA_DQ<26>
J 0
(-1540 4160);
DISPLAY 0.659574 (-1540 4160);
PAINT MONO (-1540 4160);
DISPLAY INVISIBLE (-1540 4160);
FORCEPROP 1 LASTPIN (-1550 4150) BN 26
J 0
(-1562 4158);
DISPLAY 0.680851 (-1562 4158);
PAINT GREEN (-1562 4158);
FORCEPROP 2 LAST CDS_LIB standard
J 0
(-1500 4150);
DISPLAY INVISIBLE (-1500 4150);
FORCEPROP 1 LAST BODY_TYPE PLUMBING
J 0
(-1500 4200);
DISPLAY 0.872340 (-1500 4200);
PAINT GREEN (-1500 4200);
DISPLAY INVISIBLE (-1500 4200);
FORCEPROP 1 LAST HDL_TAP TRUE
J 0
(-1175 4025);
DISPLAY 0.872340 (-1175 4025);
DISPLAY INVISIBLE (-1175 4025);
FORCEPROP 1 LAST PATH I122
J 0
(-1502 4150);
DISPLAY 0.872340 (-1502 4150);
PAINT GREEN (-1502 4150);
DISPLAY INVISIBLE (-1502 4150);
FORCEADD TAP..1
(-1500 4200);
FORCEPROP 3 LASTPIN (-1550 4200) SIG_NAME M_G_CPU1_SA_DQ<27>
J 0
(-1540 4210);
DISPLAY 0.659574 (-1540 4210);
PAINT MONO (-1540 4210);
DISPLAY INVISIBLE (-1540 4210);
FORCEPROP 1 LASTPIN (-1550 4200) BN 27
J 0
(-1562 4208);
DISPLAY 0.680851 (-1562 4208);
PAINT GREEN (-1562 4208);
FORCEPROP 2 LAST CDS_LIB standard
J 0
(-1500 4200);
DISPLAY INVISIBLE (-1500 4200);
FORCEPROP 1 LAST BODY_TYPE PLUMBING
J 0
(-1500 4250);
DISPLAY 0.872340 (-1500 4250);
PAINT GREEN (-1500 4250);
DISPLAY INVISIBLE (-1500 4250);
FORCEPROP 1 LAST HDL_TAP TRUE
J 0
(-1175 4075);
DISPLAY 0.872340 (-1175 4075);
DISPLAY INVISIBLE (-1175 4075);
FORCEPROP 1 LAST PATH I123
J 0
(-1502 4200);
DISPLAY 0.872340 (-1502 4200);
PAINT GREEN (-1502 4200);
DISPLAY INVISIBLE (-1502 4200);
FORCEADD TAP..1
(-1500 4250);
FORCEPROP 3 LASTPIN (-1550 4250) SIG_NAME M_G_CPU1_SA_DQ<28>
J 0
(-1540 4260);
DISPLAY 0.659574 (-1540 4260);
PAINT MONO (-1540 4260);
DISPLAY INVISIBLE (-1540 4260);
FORCEPROP 1 LASTPIN (-1550 4250) BN 28
J 0
(-1562 4258);
DISPLAY 0.680851 (-1562 4258);
PAINT GREEN (-1562 4258);
FORCEPROP 2 LAST CDS_LIB standard
J 0
(-1500 4250);
DISPLAY INVISIBLE (-1500 4250);
FORCEPROP 1 LAST BODY_TYPE PLUMBING
J 0
(-1500 4300);
DISPLAY 0.872340 (-1500 4300);
PAINT GREEN (-1500 4300);
DISPLAY INVISIBLE (-1500 4300);
FORCEPROP 1 LAST HDL_TAP TRUE
J 0
(-1175 4125);
DISPLAY 0.872340 (-1175 4125);
DISPLAY INVISIBLE (-1175 4125);
FORCEPROP 1 LAST PATH I124
J 0
(-1502 4250);
DISPLAY 0.872340 (-1502 4250);
PAINT GREEN (-1502 4250);
DISPLAY INVISIBLE (-1502 4250);
FORCEADD TAP..1
(-1500 4400);
FORCEPROP 3 LASTPIN (-1550 4400) SIG_NAME M_G_CPU1_SA_DQ<31>
J 0
(-1540 4410);
DISPLAY 0.659574 (-1540 4410);
PAINT MONO (-1540 4410);
DISPLAY INVISIBLE (-1540 4410);
FORCEPROP 1 LASTPIN (-1550 4400) BN 31
J 0
(-1562 4408);
DISPLAY 0.680851 (-1562 4408);
PAINT GREEN (-1562 4408);
FORCEPROP 2 LAST CDS_LIB standard
J 0
(-1500 4400);
DISPLAY INVISIBLE (-1500 4400);
FORCEPROP 1 LAST BODY_TYPE PLUMBING
J 0
(-1500 4450);
DISPLAY 0.872340 (-1500 4450);
PAINT GREEN (-1500 4450);
DISPLAY INVISIBLE (-1500 4450);
FORCEPROP 1 LAST HDL_TAP TRUE
J 0
(-1175 4275);
DISPLAY 0.872340 (-1175 4275);
DISPLAY INVISIBLE (-1175 4275);
FORCEPROP 1 LAST PATH I125
J 0
(-1502 4400);
DISPLAY 0.872340 (-1502 4400);
PAINT GREEN (-1502 4400);
DISPLAY INVISIBLE (-1502 4400);
FORCEADD TAP..1
(-1500 4350);
FORCEPROP 3 LASTPIN (-1550 4350) SIG_NAME M_G_CPU1_SA_DQ<30>
J 0
(-1540 4360);
DISPLAY 0.659574 (-1540 4360);
PAINT MONO (-1540 4360);
DISPLAY INVISIBLE (-1540 4360);
FORCEPROP 1 LASTPIN (-1550 4350) BN 30
J 0
(-1562 4358);
DISPLAY 0.680851 (-1562 4358);
PAINT GREEN (-1562 4358);
FORCEPROP 2 LAST CDS_LIB standard
J 0
(-1500 4350);
DISPLAY INVISIBLE (-1500 4350);
FORCEPROP 1 LAST BODY_TYPE PLUMBING
J 0
(-1500 4400);
DISPLAY 0.872340 (-1500 4400);
PAINT GREEN (-1500 4400);
DISPLAY INVISIBLE (-1500 4400);
FORCEPROP 1 LAST HDL_TAP TRUE
J 0
(-1175 4225);
DISPLAY 0.872340 (-1175 4225);
DISPLAY INVISIBLE (-1175 4225);
FORCEPROP 1 LAST PATH I126
J 0
(-1502 4350);
DISPLAY 0.872340 (-1502 4350);
PAINT GREEN (-1502 4350);
DISPLAY INVISIBLE (-1502 4350);
FORCEADD TAP..1
(-1500 4300);
FORCEPROP 3 LASTPIN (-1550 4300) SIG_NAME M_G_CPU1_SA_DQ<29>
J 0
(-1540 4310);
DISPLAY 0.659574 (-1540 4310);
PAINT MONO (-1540 4310);
DISPLAY INVISIBLE (-1540 4310);
FORCEPROP 1 LASTPIN (-1550 4300) BN 29
J 0
(-1562 4308);
DISPLAY 0.680851 (-1562 4308);
PAINT GREEN (-1562 4308);
FORCEPROP 2 LAST CDS_LIB standard
J 0
(-1500 4300);
DISPLAY INVISIBLE (-1500 4300);
FORCEPROP 1 LAST BODY_TYPE PLUMBING
J 0
(-1500 4350);
DISPLAY 0.872340 (-1500 4350);
PAINT GREEN (-1500 4350);
DISPLAY INVISIBLE (-1500 4350);
FORCEPROP 1 LAST HDL_TAP TRUE
J 0
(-1175 4175);
DISPLAY 0.872340 (-1175 4175);
DISPLAY INVISIBLE (-1175 4175);
FORCEPROP 1 LAST PATH I127
J 0
(-1502 4300);
DISPLAY 0.872340 (-1502 4300);
PAINT GREEN (-1502 4300);
DISPLAY INVISIBLE (-1502 4300);
FORCEADD OFFPAGE..3
(-675 4425);
FORCEPROP 2 LAST $XR1 110 
J 0
(-371 4425);
DISPLAY 0.638298 (-371 4425);
PAINT MONO (-371 4425);
FORCEPROP 2 LAST $XR0 57 
J 0
(-461 4425);
DISPLAY 0.638298 (-461 4425);
PAINT MONO (-461 4425);
FORCEPROP 2 LAST CDS_LIB standard
J 2
(-675 4425);
DISPLAY INVISIBLE (-675 4425);
FORCEPROP 1 LAST OFFPAGE TRUE
J 0
(-350 4300);
DISPLAY 0.872340 (-350 4300);
DISPLAY INVISIBLE (-350 4300);
FORCEPROP 1 LAST COMMENT_BODY TRUE
J 0
(-725 4325);
DISPLAY 0.872340 (-725 4325);
PAINT GREEN (-725 4325);
DISPLAY INVISIBLE (-725 4325);
FORCEPROP 2 LAST PATH I128
J 0
(-475 4500);
DISPLAY 1.021277 (-475 4500);
DISPLAY INVISIBLE (-475 4500);
FORCEADD OFFPAGE..3
R 2
(-4075 3025);
FORCEPROP 2 LAST $XR1 110 
J 0
(-4444 3025);
DISPLAY 0.638298 (-4444 3025);
PAINT MONO (-4444 3025);
FORCEPROP 2 LAST $XR0 57 
J 0
(-4324 3025);
DISPLAY 0.638298 (-4324 3025);
PAINT MONO (-4324 3025);
FORCEPROP 2 LAST CDS_LIB standard
J 0
(-4075 3025);
PAINT MONO (-4075 3025);
DISPLAY INVISIBLE (-4075 3025);
FORCEPROP 1 LAST OFFPAGE TRUE
J 2
(-4400 2900);
DISPLAY 0.872340 (-4400 2900);
DISPLAY INVISIBLE (-4400 2900);
FORCEPROP 1 LAST COMMENT_BODY TRUE
J 2
(-4025 2925);
DISPLAY 0.872340 (-4025 2925);
PAINT GREEN (-4025 2925);
DISPLAY INVISIBLE (-4025 2925);
FORCEPROP 2 LAST PATH I13
J 0
(-4025 3100);
DISPLAY 1.021277 (-4025 3100);
DISPLAY INVISIBLE (-4025 3100);
FORCEADD TAP..1
(1250 2450);
FORCEPROP 3 LASTPIN (1200 2450) SIG_NAME M_G_CPU1_SB_DQS_DP<0>
J 0
(1210 2460);
DISPLAY 0.659574 (1210 2460);
PAINT MONO (1210 2460);
DISPLAY INVISIBLE (1210 2460);
FORCEPROP 1 LASTPIN (1200 2450) BN 0
J 0
(1188 2458);
DISPLAY 0.680851 (1188 2458);
PAINT GREEN (1188 2458);
FORCEPROP 2 LAST CDS_LIB standard
J 0
(1250 2450);
PAINT MONO (1250 2450);
DISPLAY INVISIBLE (1250 2450);
FORCEPROP 1 LAST BODY_TYPE PLUMBING
J 0
(1250 2500);
DISPLAY 0.872340 (1250 2500);
PAINT GREEN (1250 2500);
DISPLAY INVISIBLE (1250 2500);
FORCEPROP 1 LAST HDL_TAP TRUE
J 0
(1575 2325);
DISPLAY 0.872340 (1575 2325);
DISPLAY INVISIBLE (1575 2325);
FORCEPROP 1 LAST PATH I130
J 0
(1248 2450);
DISPLAY 0.872340 (1248 2450);
PAINT GREEN (1248 2450);
DISPLAY INVISIBLE (1248 2450);
FORCEADD TAP..1
(1250 2550);
FORCEPROP 3 LASTPIN (1200 2550) SIG_NAME M_G_CPU1_SB_DQS_DP<1>
J 0
(1210 2560);
DISPLAY 0.659574 (1210 2560);
PAINT MONO (1210 2560);
DISPLAY INVISIBLE (1210 2560);
FORCEPROP 1 LASTPIN (1200 2550) BN 1
J 0
(1188 2558);
DISPLAY 0.680851 (1188 2558);
PAINT GREEN (1188 2558);
FORCEPROP 2 LAST CDS_LIB standard
J 0
(1250 2550);
DISPLAY INVISIBLE (1250 2550);
FORCEPROP 1 LAST BODY_TYPE PLUMBING
J 0
(1250 2600);
DISPLAY 0.872340 (1250 2600);
PAINT GREEN (1250 2600);
DISPLAY INVISIBLE (1250 2600);
FORCEPROP 1 LAST HDL_TAP TRUE
J 0
(1575 2425);
DISPLAY 0.872340 (1575 2425);
DISPLAY INVISIBLE (1575 2425);
FORCEPROP 1 LAST PATH I131
J 0
(1248 2550);
DISPLAY 0.872340 (1248 2550);
PAINT GREEN (1248 2550);
DISPLAY INVISIBLE (1248 2550);
FORCEADD TAP..1
(1425 2500);
FORCEPROP 3 LASTPIN (1375 2500) SIG_NAME M_G_CPU1_SB_DQS_DN<1>
J 0
(1385 2510);
DISPLAY 0.659574 (1385 2510);
PAINT MONO (1385 2510);
DISPLAY INVISIBLE (1385 2510);
FORCEPROP 1 LASTPIN (1375 2500) BN 1
J 0
(1363 2508);
DISPLAY 0.680851 (1363 2508);
PAINT GREEN (1363 2508);
FORCEPROP 2 LAST CDS_LIB standard
J 0
(1425 2500);
DISPLAY INVISIBLE (1425 2500);
FORCEPROP 1 LAST BODY_TYPE PLUMBING
J 0
(1425 2550);
DISPLAY 0.872340 (1425 2550);
PAINT GREEN (1425 2550);
DISPLAY INVISIBLE (1425 2550);
FORCEPROP 1 LAST HDL_TAP TRUE
J 0
(1750 2375);
DISPLAY 0.872340 (1750 2375);
DISPLAY INVISIBLE (1750 2375);
FORCEPROP 1 LAST PATH I132
J 0
(1423 2500);
DISPLAY 0.872340 (1423 2500);
PAINT GREEN (1423 2500);
DISPLAY INVISIBLE (1423 2500);
FORCEADD TAP..1
(1425 2600);
FORCEPROP 3 LASTPIN (1375 2600) SIG_NAME M_G_CPU1_SB_DQS_DN<2>
J 0
(1385 2610);
DISPLAY 0.659574 (1385 2610);
PAINT MONO (1385 2610);
DISPLAY INVISIBLE (1385 2610);
FORCEPROP 1 LASTPIN (1375 2600) BN 2
J 0
(1363 2608);
DISPLAY 0.680851 (1363 2608);
PAINT GREEN (1363 2608);
FORCEPROP 2 LAST CDS_LIB standard
J 0
(1425 2600);
DISPLAY INVISIBLE (1425 2600);
FORCEPROP 1 LAST BODY_TYPE PLUMBING
J 0
(1425 2650);
DISPLAY 0.872340 (1425 2650);
PAINT GREEN (1425 2650);
DISPLAY INVISIBLE (1425 2650);
FORCEPROP 1 LAST HDL_TAP TRUE
J 0
(1750 2475);
DISPLAY 0.872340 (1750 2475);
DISPLAY INVISIBLE (1750 2475);
FORCEPROP 1 LAST PATH I133
J 0
(1423 2600);
DISPLAY 0.872340 (1423 2600);
PAINT GREEN (1423 2600);
DISPLAY INVISIBLE (1423 2600);
FORCEADD TAP..1
(1425 2400);
FORCEPROP 3 LASTPIN (1375 2400) SIG_NAME M_G_CPU1_SB_DQS_DN<0>
J 0
(1385 2410);
DISPLAY 0.659574 (1385 2410);
PAINT MONO (1385 2410);
DISPLAY INVISIBLE (1385 2410);
FORCEPROP 1 LASTPIN (1375 2400) BN 0
J 0
(1363 2408);
DISPLAY 0.680851 (1363 2408);
PAINT GREEN (1363 2408);
FORCEPROP 2 LAST CDS_LIB standard
J 0
(1425 2400);
PAINT MONO (1425 2400);
DISPLAY INVISIBLE (1425 2400);
FORCEPROP 1 LAST BODY_TYPE PLUMBING
J 0
(1425 2450);
DISPLAY 0.872340 (1425 2450);
PAINT GREEN (1425 2450);
DISPLAY INVISIBLE (1425 2450);
FORCEPROP 1 LAST HDL_TAP TRUE
J 0
(1750 2275);
DISPLAY 0.872340 (1750 2275);
DISPLAY INVISIBLE (1750 2275);
FORCEPROP 1 LAST PATH I134
J 0
(1423 2400);
DISPLAY 0.872340 (1423 2400);
PAINT GREEN (1423 2400);
DISPLAY INVISIBLE (1423 2400);
FORCEADD TAP..1
(1250 2650);
FORCEPROP 3 LASTPIN (1200 2650) SIG_NAME M_G_CPU1_SB_DQS_DP<2>
J 0
(1210 2660);
DISPLAY 0.659574 (1210 2660);
PAINT MONO (1210 2660);
DISPLAY INVISIBLE (1210 2660);
FORCEPROP 1 LASTPIN (1200 2650) BN 2
J 0
(1188 2658);
DISPLAY 0.680851 (1188 2658);
PAINT GREEN (1188 2658);
FORCEPROP 2 LAST CDS_LIB standard
J 0
(1250 2650);
DISPLAY INVISIBLE (1250 2650);
FORCEPROP 1 LAST BODY_TYPE PLUMBING
J 0
(1250 2700);
DISPLAY 0.872340 (1250 2700);
PAINT GREEN (1250 2700);
DISPLAY INVISIBLE (1250 2700);
FORCEPROP 1 LAST HDL_TAP TRUE
J 0
(1575 2525);
DISPLAY 0.872340 (1575 2525);
DISPLAY INVISIBLE (1575 2525);
FORCEPROP 1 LAST PATH I135
J 0
(1248 2650);
DISPLAY 0.872340 (1248 2650);
PAINT GREEN (1248 2650);
DISPLAY INVISIBLE (1248 2650);
FORCEADD TAP..1
(1250 2750);
FORCEPROP 3 LASTPIN (1200 2750) SIG_NAME M_G_CPU1_SB_DQS_DP<3>
J 0
(1210 2760);
DISPLAY 0.659574 (1210 2760);
PAINT MONO (1210 2760);
DISPLAY INVISIBLE (1210 2760);
FORCEPROP 1 LASTPIN (1200 2750) BN 3
J 0
(1188 2758);
DISPLAY 0.680851 (1188 2758);
PAINT GREEN (1188 2758);
FORCEPROP 2 LAST CDS_LIB standard
J 0
(1250 2750);
PAINT MONO (1250 2750);
DISPLAY INVISIBLE (1250 2750);
FORCEPROP 1 LAST BODY_TYPE PLUMBING
J 0
(1250 2800);
DISPLAY 0.872340 (1250 2800);
PAINT GREEN (1250 2800);
DISPLAY INVISIBLE (1250 2800);
FORCEPROP 1 LAST HDL_TAP TRUE
J 0
(1575 2625);
DISPLAY 0.872340 (1575 2625);
DISPLAY INVISIBLE (1575 2625);
FORCEPROP 1 LAST PATH I136
J 0
(1248 2750);
DISPLAY 0.872340 (1248 2750);
PAINT GREEN (1248 2750);
DISPLAY INVISIBLE (1248 2750);
FORCEADD TAP..1
(1250 2850);
FORCEPROP 3 LASTPIN (1200 2850) SIG_NAME M_G_CPU1_SB_DQS_DP<4>
J 0
(1210 2860);
DISPLAY 0.659574 (1210 2860);
PAINT MONO (1210 2860);
DISPLAY INVISIBLE (1210 2860);
FORCEPROP 1 LASTPIN (1200 2850) BN 4
J 0
(1188 2858);
DISPLAY 0.680851 (1188 2858);
PAINT GREEN (1188 2858);
FORCEPROP 2 LAST CDS_LIB standard
J 0
(1250 2850);
PAINT MONO (1250 2850);
DISPLAY INVISIBLE (1250 2850);
FORCEPROP 1 LAST BODY_TYPE PLUMBING
J 0
(1250 2900);
DISPLAY 0.872340 (1250 2900);
PAINT GREEN (1250 2900);
DISPLAY INVISIBLE (1250 2900);
FORCEPROP 1 LAST HDL_TAP TRUE
J 0
(1575 2725);
DISPLAY 0.872340 (1575 2725);
DISPLAY INVISIBLE (1575 2725);
FORCEPROP 1 LAST PATH I137
J 0
(1248 2850);
DISPLAY 0.872340 (1248 2850);
PAINT GREEN (1248 2850);
DISPLAY INVISIBLE (1248 2850);
FORCEADD TAP..1
(1250 2950);
FORCEPROP 3 LASTPIN (1200 2950) SIG_NAME M_G_CPU1_SB_DQS_DP<5>
J 0
(1210 2960);
DISPLAY 0.659574 (1210 2960);
PAINT MONO (1210 2960);
DISPLAY INVISIBLE (1210 2960);
FORCEPROP 1 LASTPIN (1200 2950) BN 5
J 0
(1188 2958);
DISPLAY 0.680851 (1188 2958);
PAINT GREEN (1188 2958);
FORCEPROP 2 LAST CDS_LIB standard
J 0
(1250 2950);
DISPLAY INVISIBLE (1250 2950);
FORCEPROP 1 LAST BODY_TYPE PLUMBING
J 0
(1250 3000);
DISPLAY 0.872340 (1250 3000);
PAINT GREEN (1250 3000);
DISPLAY INVISIBLE (1250 3000);
FORCEPROP 1 LAST HDL_TAP TRUE
J 0
(1575 2825);
DISPLAY 0.872340 (1575 2825);
DISPLAY INVISIBLE (1575 2825);
FORCEPROP 1 LAST PATH I138
J 0
(1248 2950);
DISPLAY 0.872340 (1248 2950);
PAINT GREEN (1248 2950);
DISPLAY INVISIBLE (1248 2950);
FORCEADD TAP..1
(1250 3050);
FORCEPROP 3 LASTPIN (1200 3050) SIG_NAME M_G_CPU1_SB_DQS_DP<6>
J 0
(1210 3060);
DISPLAY 0.659574 (1210 3060);
PAINT MONO (1210 3060);
DISPLAY INVISIBLE (1210 3060);
FORCEPROP 1 LASTPIN (1200 3050) BN 6
J 0
(1188 3058);
DISPLAY 0.680851 (1188 3058);
PAINT GREEN (1188 3058);
FORCEPROP 2 LAST CDS_LIB standard
J 0
(1250 3050);
DISPLAY INVISIBLE (1250 3050);
FORCEPROP 1 LAST BODY_TYPE PLUMBING
J 0
(1250 3100);
DISPLAY 0.872340 (1250 3100);
PAINT GREEN (1250 3100);
DISPLAY INVISIBLE (1250 3100);
FORCEPROP 1 LAST HDL_TAP TRUE
J 0
(1575 2925);
DISPLAY 0.872340 (1575 2925);
DISPLAY INVISIBLE (1575 2925);
FORCEPROP 1 LAST PATH I139
J 0
(1248 3050);
DISPLAY 0.872340 (1248 3050);
PAINT GREEN (1248 3050);
DISPLAY INVISIBLE (1248 3050);
FORCEADD OFFPAGE..1
(-4075 3100);
FORCEPROP 2 LAST $XR0 57 
J 0
(-4296 3100);
DISPLAY 0.638298 (-4296 3100);
PAINT MONO (-4296 3100);
FORCEPROP 2 LAST CDS_LIB standard
J 0
(-4075 3100);
PAINT MONO (-4075 3100);
DISPLAY INVISIBLE (-4075 3100);
FORCEPROP 1 LAST OFFPAGE TRUE
J 0
(-3750 2975);
DISPLAY 0.872340 (-3750 2975);
DISPLAY INVISIBLE (-3750 2975);
FORCEPROP 1 LAST COMMENT_BODY TRUE
J 0
(-3950 3000);
DISPLAY 0.872340 (-3950 3000);
PAINT GREEN (-3950 3000);
DISPLAY INVISIBLE (-3950 3000);
FORCEPROP 2 LAST PATH I14
J 0
(-4025 3175);
DISPLAY 1.021277 (-4025 3175);
DISPLAY INVISIBLE (-4025 3175);
FORCEADD TAP..1
(1425 2700);
FORCEPROP 3 LASTPIN (1375 2700) SIG_NAME M_G_CPU1_SB_DQS_DN<3>
J 0
(1385 2710);
DISPLAY 0.659574 (1385 2710);
PAINT MONO (1385 2710);
DISPLAY INVISIBLE (1385 2710);
FORCEPROP 1 LASTPIN (1375 2700) BN 3
J 0
(1363 2708);
DISPLAY 0.680851 (1363 2708);
PAINT GREEN (1363 2708);
FORCEPROP 2 LAST CDS_LIB standard
J 0
(1425 2700);
PAINT MONO (1425 2700);
DISPLAY INVISIBLE (1425 2700);
FORCEPROP 1 LAST BODY_TYPE PLUMBING
J 0
(1425 2750);
DISPLAY 0.872340 (1425 2750);
PAINT GREEN (1425 2750);
DISPLAY INVISIBLE (1425 2750);
FORCEPROP 1 LAST HDL_TAP TRUE
J 0
(1750 2575);
DISPLAY 0.872340 (1750 2575);
DISPLAY INVISIBLE (1750 2575);
FORCEPROP 1 LAST PATH I140
J 0
(1423 2700);
DISPLAY 0.872340 (1423 2700);
PAINT GREEN (1423 2700);
DISPLAY INVISIBLE (1423 2700);
FORCEADD TAP..1
(1425 2800);
FORCEPROP 3 LASTPIN (1375 2800) SIG_NAME M_G_CPU1_SB_DQS_DN<4>
J 0
(1385 2810);
DISPLAY 0.659574 (1385 2810);
PAINT MONO (1385 2810);
DISPLAY INVISIBLE (1385 2810);
FORCEPROP 1 LASTPIN (1375 2800) BN 4
J 0
(1363 2808);
DISPLAY 0.680851 (1363 2808);
PAINT GREEN (1363 2808);
FORCEPROP 2 LAST CDS_LIB standard
J 0
(1425 2800);
PAINT MONO (1425 2800);
DISPLAY INVISIBLE (1425 2800);
FORCEPROP 1 LAST BODY_TYPE PLUMBING
J 0
(1425 2850);
DISPLAY 0.872340 (1425 2850);
PAINT GREEN (1425 2850);
DISPLAY INVISIBLE (1425 2850);
FORCEPROP 1 LAST HDL_TAP TRUE
J 0
(1750 2675);
DISPLAY 0.872340 (1750 2675);
DISPLAY INVISIBLE (1750 2675);
FORCEPROP 1 LAST PATH I141
J 0
(1423 2800);
DISPLAY 0.872340 (1423 2800);
PAINT GREEN (1423 2800);
DISPLAY INVISIBLE (1423 2800);
FORCEADD TAP..1
(1425 2900);
FORCEPROP 3 LASTPIN (1375 2900) SIG_NAME M_G_CPU1_SB_DQS_DN<5>
J 0
(1385 2910);
DISPLAY 0.659574 (1385 2910);
PAINT MONO (1385 2910);
DISPLAY INVISIBLE (1385 2910);
FORCEPROP 1 LASTPIN (1375 2900) BN 5
J 0
(1363 2908);
DISPLAY 0.680851 (1363 2908);
PAINT GREEN (1363 2908);
FORCEPROP 2 LAST CDS_LIB standard
J 0
(1425 2900);
DISPLAY INVISIBLE (1425 2900);
FORCEPROP 1 LAST BODY_TYPE PLUMBING
J 0
(1425 2950);
DISPLAY 0.872340 (1425 2950);
PAINT GREEN (1425 2950);
DISPLAY INVISIBLE (1425 2950);
FORCEPROP 1 LAST HDL_TAP TRUE
J 0
(1750 2775);
DISPLAY 0.872340 (1750 2775);
DISPLAY INVISIBLE (1750 2775);
FORCEPROP 1 LAST PATH I142
J 0
(1423 2900);
DISPLAY 0.872340 (1423 2900);
PAINT GREEN (1423 2900);
DISPLAY INVISIBLE (1423 2900);
FORCEADD TAP..1
(1425 3000);
FORCEPROP 3 LASTPIN (1375 3000) SIG_NAME M_G_CPU1_SB_DQS_DN<6>
J 0
(1385 3010);
DISPLAY 0.659574 (1385 3010);
PAINT MONO (1385 3010);
DISPLAY INVISIBLE (1385 3010);
FORCEPROP 1 LASTPIN (1375 3000) BN 6
J 0
(1363 3008);
DISPLAY 0.680851 (1363 3008);
PAINT GREEN (1363 3008);
FORCEPROP 2 LAST CDS_LIB standard
J 0
(1425 3000);
DISPLAY INVISIBLE (1425 3000);
FORCEPROP 1 LAST BODY_TYPE PLUMBING
J 0
(1425 3050);
DISPLAY 0.872340 (1425 3050);
PAINT GREEN (1425 3050);
DISPLAY INVISIBLE (1425 3050);
FORCEPROP 1 LAST HDL_TAP TRUE
J 0
(1750 2875);
DISPLAY 0.872340 (1750 2875);
DISPLAY INVISIBLE (1750 2875);
FORCEPROP 1 LAST PATH I143
J 0
(1423 3000);
DISPLAY 0.872340 (1423 3000);
PAINT GREEN (1423 3000);
DISPLAY INVISIBLE (1423 3000);
FORCEADD TAP..1
(1425 3100);
FORCEPROP 3 LASTPIN (1375 3100) SIG_NAME M_G_CPU1_SB_DQS_DN<7>
J 0
(1385 3110);
DISPLAY 0.659574 (1385 3110);
PAINT MONO (1385 3110);
DISPLAY INVISIBLE (1385 3110);
FORCEPROP 1 LASTPIN (1375 3100) BN 7
J 0
(1363 3108);
DISPLAY 0.680851 (1363 3108);
PAINT GREEN (1363 3108);
FORCEPROP 2 LAST CDS_LIB standard
J 0
(1425 3100);
DISPLAY INVISIBLE (1425 3100);
FORCEPROP 1 LAST BODY_TYPE PLUMBING
J 0
(1425 3150);
DISPLAY 0.872340 (1425 3150);
PAINT GREEN (1425 3150);
DISPLAY INVISIBLE (1425 3150);
FORCEPROP 1 LAST HDL_TAP TRUE
J 0
(1750 2975);
DISPLAY 0.872340 (1750 2975);
DISPLAY INVISIBLE (1750 2975);
FORCEPROP 1 LAST PATH I144
J 0
(1423 3100);
DISPLAY 0.872340 (1423 3100);
PAINT GREEN (1423 3100);
DISPLAY INVISIBLE (1423 3100);
FORCEADD TAP..1
(1250 3150);
FORCEPROP 3 LASTPIN (1200 3150) SIG_NAME M_G_CPU1_SB_DQS_DP<7>
J 0
(1210 3160);
DISPLAY 0.659574 (1210 3160);
PAINT MONO (1210 3160);
DISPLAY INVISIBLE (1210 3160);
FORCEPROP 1 LASTPIN (1200 3150) BN 7
J 0
(1188 3158);
DISPLAY 0.680851 (1188 3158);
PAINT GREEN (1188 3158);
FORCEPROP 2 LAST CDS_LIB standard
J 0
(1250 3150);
DISPLAY INVISIBLE (1250 3150);
FORCEPROP 1 LAST BODY_TYPE PLUMBING
J 0
(1250 3200);
DISPLAY 0.872340 (1250 3200);
PAINT GREEN (1250 3200);
DISPLAY INVISIBLE (1250 3200);
FORCEPROP 1 LAST HDL_TAP TRUE
J 0
(1575 3025);
DISPLAY 0.872340 (1575 3025);
DISPLAY INVISIBLE (1575 3025);
FORCEPROP 1 LAST PATH I145
J 0
(1248 3150);
DISPLAY 0.872340 (1248 3150);
PAINT GREEN (1248 3150);
DISPLAY INVISIBLE (1248 3150);
FORCEADD TAP..1
(1250 3250);
FORCEPROP 3 LASTPIN (1200 3250) SIG_NAME M_G_CPU1_SB_DQS_DP<8>
J 0
(1210 3260);
DISPLAY 0.659574 (1210 3260);
PAINT MONO (1210 3260);
DISPLAY INVISIBLE (1210 3260);
FORCEPROP 1 LASTPIN (1200 3250) BN 8
J 0
(1188 3258);
DISPLAY 0.680851 (1188 3258);
PAINT GREEN (1188 3258);
FORCEPROP 2 LAST CDS_LIB standard
J 0
(1250 3250);
DISPLAY INVISIBLE (1250 3250);
FORCEPROP 1 LAST BODY_TYPE PLUMBING
J 0
(1250 3300);
DISPLAY 0.872340 (1250 3300);
PAINT GREEN (1250 3300);
DISPLAY INVISIBLE (1250 3300);
FORCEPROP 1 LAST HDL_TAP TRUE
J 0
(1575 3125);
DISPLAY 0.872340 (1575 3125);
DISPLAY INVISIBLE (1575 3125);
FORCEPROP 1 LAST PATH I146
J 0
(1248 3250);
DISPLAY 0.872340 (1248 3250);
PAINT GREEN (1248 3250);
DISPLAY INVISIBLE (1248 3250);
FORCEADD TAP..1
(1250 3350);
FORCEPROP 3 LASTPIN (1200 3350) SIG_NAME M_G_CPU1_SB_DQS_DP<9>
J 0
(1210 3360);
DISPLAY 0.659574 (1210 3360);
PAINT MONO (1210 3360);
DISPLAY INVISIBLE (1210 3360);
FORCEPROP 1 LASTPIN (1200 3350) BN 9
J 0
(1188 3358);
DISPLAY 0.680851 (1188 3358);
PAINT GREEN (1188 3358);
FORCEPROP 2 LAST CDS_LIB standard
J 0
(1250 3350);
DISPLAY INVISIBLE (1250 3350);
FORCEPROP 1 LAST BODY_TYPE PLUMBING
J 0
(1250 3400);
DISPLAY 0.872340 (1250 3400);
PAINT GREEN (1250 3400);
DISPLAY INVISIBLE (1250 3400);
FORCEPROP 1 LAST HDL_TAP TRUE
J 0
(1575 3225);
DISPLAY 0.872340 (1575 3225);
DISPLAY INVISIBLE (1575 3225);
FORCEPROP 1 LAST PATH I147
J 0
(1248 3350);
DISPLAY 0.872340 (1248 3350);
PAINT GREEN (1248 3350);
DISPLAY INVISIBLE (1248 3350);
FORCEADD TAP..1
(1250 3500);
FORCEPROP 3 LASTPIN (1200 3500) SIG_NAME M_G_CPU1_SA_DQS_DP<0>
J 0
(1210 3510);
DISPLAY 0.659574 (1210 3510);
PAINT MONO (1210 3510);
DISPLAY INVISIBLE (1210 3510);
FORCEPROP 1 LASTPIN (1200 3500) BN 0
J 0
(1188 3508);
DISPLAY 0.680851 (1188 3508);
PAINT GREEN (1188 3508);
FORCEPROP 2 LAST CDS_LIB standard
J 0
(1250 3500);
PAINT MONO (1250 3500);
DISPLAY INVISIBLE (1250 3500);
FORCEPROP 1 LAST BODY_TYPE PLUMBING
J 0
(1250 3550);
DISPLAY 0.872340 (1250 3550);
PAINT GREEN (1250 3550);
DISPLAY INVISIBLE (1250 3550);
FORCEPROP 1 LAST HDL_TAP TRUE
J 0
(1575 3375);
DISPLAY 0.872340 (1575 3375);
DISPLAY INVISIBLE (1575 3375);
FORCEPROP 1 LAST PATH I148
J 0
(1248 3500);
DISPLAY 0.872340 (1248 3500);
PAINT GREEN (1248 3500);
DISPLAY INVISIBLE (1248 3500);
FORCEADD TAP..1
(1250 3600);
FORCEPROP 3 LASTPIN (1200 3600) SIG_NAME M_G_CPU1_SA_DQS_DP<1>
J 0
(1210 3610);
DISPLAY 0.659574 (1210 3610);
PAINT MONO (1210 3610);
DISPLAY INVISIBLE (1210 3610);
FORCEPROP 1 LASTPIN (1200 3600) BN 1
J 0
(1188 3608);
DISPLAY 0.680851 (1188 3608);
PAINT GREEN (1188 3608);
FORCEPROP 2 LAST CDS_LIB standard
J 0
(1250 3600);
DISPLAY INVISIBLE (1250 3600);
FORCEPROP 1 LAST BODY_TYPE PLUMBING
J 0
(1250 3650);
DISPLAY 0.872340 (1250 3650);
PAINT GREEN (1250 3650);
DISPLAY INVISIBLE (1250 3650);
FORCEPROP 1 LAST HDL_TAP TRUE
J 0
(1575 3475);
DISPLAY 0.872340 (1575 3475);
DISPLAY INVISIBLE (1575 3475);
FORCEPROP 1 LAST PATH I149
J 0
(1248 3600);
DISPLAY 0.872340 (1248 3600);
PAINT GREEN (1248 3600);
DISPLAY INVISIBLE (1248 3600);
FORCEADD OFFPAGE..1
(-4075 3150);
FORCEPROP 2 LAST $XR0 57 
J 0
(-4296 3150);
DISPLAY 0.638298 (-4296 3150);
PAINT MONO (-4296 3150);
FORCEPROP 2 LAST CDS_LIB standard
J 0
(-4075 3150);
PAINT MONO (-4075 3150);
DISPLAY INVISIBLE (-4075 3150);
FORCEPROP 1 LAST OFFPAGE TRUE
J 0
(-3750 3025);
DISPLAY 0.872340 (-3750 3025);
DISPLAY INVISIBLE (-3750 3025);
FORCEPROP 1 LAST COMMENT_BODY TRUE
J 0
(-3950 3050);
DISPLAY 0.872340 (-3950 3050);
PAINT GREEN (-3950 3050);
DISPLAY INVISIBLE (-3950 3050);
FORCEPROP 2 LAST PATH I15
J 0
(-4025 3225);
DISPLAY 1.021277 (-4025 3225);
DISPLAY INVISIBLE (-4025 3225);
FORCEADD TAP..1
(1425 3200);
FORCEPROP 3 LASTPIN (1375 3200) SIG_NAME M_G_CPU1_SB_DQS_DN<8>
J 0
(1385 3210);
DISPLAY 0.659574 (1385 3210);
PAINT MONO (1385 3210);
DISPLAY INVISIBLE (1385 3210);
FORCEPROP 1 LASTPIN (1375 3200) BN 8
J 0
(1363 3208);
DISPLAY 0.680851 (1363 3208);
PAINT GREEN (1363 3208);
FORCEPROP 2 LAST CDS_LIB standard
J 0
(1425 3200);
DISPLAY INVISIBLE (1425 3200);
FORCEPROP 1 LAST BODY_TYPE PLUMBING
J 0
(1425 3250);
DISPLAY 0.872340 (1425 3250);
PAINT GREEN (1425 3250);
DISPLAY INVISIBLE (1425 3250);
FORCEPROP 1 LAST HDL_TAP TRUE
J 0
(1750 3075);
DISPLAY 0.872340 (1750 3075);
DISPLAY INVISIBLE (1750 3075);
FORCEPROP 1 LAST PATH I150
J 0
(1423 3200);
DISPLAY 0.872340 (1423 3200);
PAINT GREEN (1423 3200);
DISPLAY INVISIBLE (1423 3200);
FORCEADD TAP..1
(1425 3300);
FORCEPROP 3 LASTPIN (1375 3300) SIG_NAME M_G_CPU1_SB_DQS_DN<9>
J 0
(1385 3310);
DISPLAY 0.659574 (1385 3310);
PAINT MONO (1385 3310);
DISPLAY INVISIBLE (1385 3310);
FORCEPROP 1 LASTPIN (1375 3300) BN 9
J 0
(1363 3308);
DISPLAY 0.680851 (1363 3308);
PAINT GREEN (1363 3308);
FORCEPROP 2 LAST CDS_LIB standard
J 0
(1425 3300);
DISPLAY INVISIBLE (1425 3300);
FORCEPROP 1 LAST BODY_TYPE PLUMBING
J 0
(1425 3350);
DISPLAY 0.872340 (1425 3350);
PAINT GREEN (1425 3350);
DISPLAY INVISIBLE (1425 3350);
FORCEPROP 1 LAST HDL_TAP TRUE
J 0
(1750 3175);
DISPLAY 0.872340 (1750 3175);
DISPLAY INVISIBLE (1750 3175);
FORCEPROP 1 LAST PATH I151
J 0
(1423 3300);
DISPLAY 0.872340 (1423 3300);
PAINT GREEN (1423 3300);
DISPLAY INVISIBLE (1423 3300);
FORCEADD TAP..1
(1425 3550);
FORCEPROP 3 LASTPIN (1375 3550) SIG_NAME M_G_CPU1_SA_DQS_DN<1>
J 0
(1385 3560);
DISPLAY 0.659574 (1385 3560);
PAINT MONO (1385 3560);
DISPLAY INVISIBLE (1385 3560);
FORCEPROP 1 LASTPIN (1375 3550) BN 1
J 0
(1363 3558);
DISPLAY 0.680851 (1363 3558);
PAINT GREEN (1363 3558);
FORCEPROP 2 LAST CDS_LIB standard
J 0
(1425 3550);
DISPLAY INVISIBLE (1425 3550);
FORCEPROP 1 LAST BODY_TYPE PLUMBING
J 0
(1425 3600);
DISPLAY 0.872340 (1425 3600);
PAINT GREEN (1425 3600);
DISPLAY INVISIBLE (1425 3600);
FORCEPROP 1 LAST HDL_TAP TRUE
J 0
(1750 3425);
DISPLAY 0.872340 (1750 3425);
DISPLAY INVISIBLE (1750 3425);
FORCEPROP 1 LAST PATH I152
J 0
(1423 3550);
DISPLAY 0.872340 (1423 3550);
PAINT GREEN (1423 3550);
DISPLAY INVISIBLE (1423 3550);
FORCEADD TAP..1
(1425 3450);
FORCEPROP 3 LASTPIN (1375 3450) SIG_NAME M_G_CPU1_SA_DQS_DN<0>
J 0
(1385 3460);
DISPLAY 0.659574 (1385 3460);
PAINT MONO (1385 3460);
DISPLAY INVISIBLE (1385 3460);
FORCEPROP 1 LASTPIN (1375 3450) BN 0
J 0
(1363 3458);
DISPLAY 0.680851 (1363 3458);
PAINT GREEN (1363 3458);
FORCEPROP 2 LAST CDS_LIB standard
J 0
(1425 3450);
PAINT MONO (1425 3450);
DISPLAY INVISIBLE (1425 3450);
FORCEPROP 1 LAST BODY_TYPE PLUMBING
J 0
(1425 3500);
DISPLAY 0.872340 (1425 3500);
PAINT GREEN (1425 3500);
DISPLAY INVISIBLE (1425 3500);
FORCEPROP 1 LAST HDL_TAP TRUE
J 0
(1750 3325);
DISPLAY 0.872340 (1750 3325);
DISPLAY INVISIBLE (1750 3325);
FORCEPROP 1 LAST PATH I153
J 0
(1423 3450);
DISPLAY 0.872340 (1423 3450);
PAINT GREEN (1423 3450);
DISPLAY INVISIBLE (1423 3450);
FORCEADD TAP..1
(1250 3700);
FORCEPROP 3 LASTPIN (1200 3700) SIG_NAME M_G_CPU1_SA_DQS_DP<2>
J 0
(1210 3710);
DISPLAY 0.659574 (1210 3710);
PAINT MONO (1210 3710);
DISPLAY INVISIBLE (1210 3710);
FORCEPROP 1 LASTPIN (1200 3700) BN 2
J 0
(1188 3708);
DISPLAY 0.680851 (1188 3708);
PAINT GREEN (1188 3708);
FORCEPROP 2 LAST CDS_LIB standard
J 0
(1250 3700);
DISPLAY INVISIBLE (1250 3700);
FORCEPROP 1 LAST BODY_TYPE PLUMBING
J 0
(1250 3750);
DISPLAY 0.872340 (1250 3750);
PAINT GREEN (1250 3750);
DISPLAY INVISIBLE (1250 3750);
FORCEPROP 1 LAST HDL_TAP TRUE
J 0
(1575 3575);
DISPLAY 0.872340 (1575 3575);
DISPLAY INVISIBLE (1575 3575);
FORCEPROP 1 LAST PATH I154
J 0
(1248 3700);
DISPLAY 0.872340 (1248 3700);
PAINT GREEN (1248 3700);
DISPLAY INVISIBLE (1248 3700);
FORCEADD TAP..1
(1250 3800);
FORCEPROP 3 LASTPIN (1200 3800) SIG_NAME M_G_CPU1_SA_DQS_DP<3>
J 0
(1210 3810);
DISPLAY 0.659574 (1210 3810);
PAINT MONO (1210 3810);
DISPLAY INVISIBLE (1210 3810);
FORCEPROP 1 LASTPIN (1200 3800) BN 3
J 0
(1188 3808);
DISPLAY 0.680851 (1188 3808);
PAINT GREEN (1188 3808);
FORCEPROP 2 LAST CDS_LIB standard
J 0
(1250 3800);
PAINT MONO (1250 3800);
DISPLAY INVISIBLE (1250 3800);
FORCEPROP 1 LAST BODY_TYPE PLUMBING
J 0
(1250 3850);
DISPLAY 0.872340 (1250 3850);
PAINT GREEN (1250 3850);
DISPLAY INVISIBLE (1250 3850);
FORCEPROP 1 LAST HDL_TAP TRUE
J 0
(1575 3675);
DISPLAY 0.872340 (1575 3675);
DISPLAY INVISIBLE (1575 3675);
FORCEPROP 1 LAST PATH I155
J 0
(1248 3800);
DISPLAY 0.872340 (1248 3800);
PAINT GREEN (1248 3800);
DISPLAY INVISIBLE (1248 3800);
FORCEADD TAP..1
(1250 3900);
FORCEPROP 3 LASTPIN (1200 3900) SIG_NAME M_G_CPU1_SA_DQS_DP<4>
J 0
(1210 3910);
DISPLAY 0.659574 (1210 3910);
PAINT MONO (1210 3910);
DISPLAY INVISIBLE (1210 3910);
FORCEPROP 1 LASTPIN (1200 3900) BN 4
J 0
(1188 3908);
DISPLAY 0.680851 (1188 3908);
PAINT GREEN (1188 3908);
FORCEPROP 2 LAST CDS_LIB standard
J 0
(1250 3900);
PAINT MONO (1250 3900);
DISPLAY INVISIBLE (1250 3900);
FORCEPROP 1 LAST BODY_TYPE PLUMBING
J 0
(1250 3950);
DISPLAY 0.872340 (1250 3950);
PAINT GREEN (1250 3950);
DISPLAY INVISIBLE (1250 3950);
FORCEPROP 1 LAST HDL_TAP TRUE
J 0
(1575 3775);
DISPLAY 0.872340 (1575 3775);
DISPLAY INVISIBLE (1575 3775);
FORCEPROP 1 LAST PATH I156
J 0
(1248 3900);
DISPLAY 0.872340 (1248 3900);
PAINT GREEN (1248 3900);
DISPLAY INVISIBLE (1248 3900);
FORCEADD TAP..1
(1250 4000);
FORCEPROP 3 LASTPIN (1200 4000) SIG_NAME M_G_CPU1_SA_DQS_DP<5>
J 0
(1210 4010);
DISPLAY 0.659574 (1210 4010);
PAINT MONO (1210 4010);
DISPLAY INVISIBLE (1210 4010);
FORCEPROP 1 LASTPIN (1200 4000) BN 5
J 0
(1188 4008);
DISPLAY 0.680851 (1188 4008);
PAINT GREEN (1188 4008);
FORCEPROP 2 LAST CDS_LIB standard
J 0
(1250 4000);
DISPLAY INVISIBLE (1250 4000);
FORCEPROP 1 LAST BODY_TYPE PLUMBING
J 0
(1250 4050);
DISPLAY 0.872340 (1250 4050);
PAINT GREEN (1250 4050);
DISPLAY INVISIBLE (1250 4050);
FORCEPROP 1 LAST HDL_TAP TRUE
J 0
(1575 3875);
DISPLAY 0.872340 (1575 3875);
DISPLAY INVISIBLE (1575 3875);
FORCEPROP 1 LAST PATH I157
J 0
(1248 4000);
DISPLAY 0.872340 (1248 4000);
PAINT GREEN (1248 4000);
DISPLAY INVISIBLE (1248 4000);
FORCEADD TAP..1
(1250 4100);
FORCEPROP 3 LASTPIN (1200 4100) SIG_NAME M_G_CPU1_SA_DQS_DP<6>
J 0
(1210 4110);
DISPLAY 0.659574 (1210 4110);
PAINT MONO (1210 4110);
DISPLAY INVISIBLE (1210 4110);
FORCEPROP 1 LASTPIN (1200 4100) BN 6
J 0
(1188 4108);
DISPLAY 0.680851 (1188 4108);
PAINT GREEN (1188 4108);
FORCEPROP 2 LAST CDS_LIB standard
J 0
(1250 4100);
DISPLAY INVISIBLE (1250 4100);
FORCEPROP 1 LAST BODY_TYPE PLUMBING
J 0
(1250 4150);
DISPLAY 0.872340 (1250 4150);
PAINT GREEN (1250 4150);
DISPLAY INVISIBLE (1250 4150);
FORCEPROP 1 LAST HDL_TAP TRUE
J 0
(1575 3975);
DISPLAY 0.872340 (1575 3975);
DISPLAY INVISIBLE (1575 3975);
FORCEPROP 1 LAST PATH I158
J 0
(1248 4100);
DISPLAY 0.872340 (1248 4100);
PAINT GREEN (1248 4100);
DISPLAY INVISIBLE (1248 4100);
FORCEADD TAP..1
(1425 3650);
FORCEPROP 3 LASTPIN (1375 3650) SIG_NAME M_G_CPU1_SA_DQS_DN<2>
J 0
(1385 3660);
DISPLAY 0.659574 (1385 3660);
PAINT MONO (1385 3660);
DISPLAY INVISIBLE (1385 3660);
FORCEPROP 1 LASTPIN (1375 3650) BN 2
J 0
(1363 3658);
DISPLAY 0.680851 (1363 3658);
PAINT GREEN (1363 3658);
FORCEPROP 2 LAST CDS_LIB standard
J 0
(1425 3650);
DISPLAY INVISIBLE (1425 3650);
FORCEPROP 1 LAST BODY_TYPE PLUMBING
J 0
(1425 3700);
DISPLAY 0.872340 (1425 3700);
PAINT GREEN (1425 3700);
DISPLAY INVISIBLE (1425 3700);
FORCEPROP 1 LAST HDL_TAP TRUE
J 0
(1750 3525);
DISPLAY 0.872340 (1750 3525);
DISPLAY INVISIBLE (1750 3525);
FORCEPROP 1 LAST PATH I159
J 0
(1423 3650);
DISPLAY 0.872340 (1423 3650);
PAINT GREEN (1423 3650);
DISPLAY INVISIBLE (1423 3650);
FORCEADD OFFPAGE..1
(-4075 3400);
FORCEPROP 2 LAST $XR0 57 
J 0
(-4296 3400);
DISPLAY 0.638298 (-4296 3400);
PAINT MONO (-4296 3400);
FORCEPROP 2 LAST CDS_LIB standard
J 0
(-4075 3400);
PAINT MONO (-4075 3400);
DISPLAY INVISIBLE (-4075 3400);
FORCEPROP 1 LAST OFFPAGE TRUE
J 0
(-3750 3275);
DISPLAY 0.872340 (-3750 3275);
DISPLAY INVISIBLE (-3750 3275);
FORCEPROP 1 LAST COMMENT_BODY TRUE
J 0
(-3950 3300);
DISPLAY 0.872340 (-3950 3300);
PAINT GREEN (-3950 3300);
DISPLAY INVISIBLE (-3950 3300);
FORCEPROP 2 LAST PATH I16
J 0
(-4025 3475);
DISPLAY 1.021277 (-4025 3475);
DISPLAY INVISIBLE (-4025 3475);
FORCEADD TAP..1
(1425 3750);
FORCEPROP 3 LASTPIN (1375 3750) SIG_NAME M_G_CPU1_SA_DQS_DN<3>
J 0
(1385 3760);
DISPLAY 0.659574 (1385 3760);
PAINT MONO (1385 3760);
DISPLAY INVISIBLE (1385 3760);
FORCEPROP 1 LASTPIN (1375 3750) BN 3
J 0
(1363 3758);
DISPLAY 0.680851 (1363 3758);
PAINT GREEN (1363 3758);
FORCEPROP 2 LAST CDS_LIB standard
J 0
(1425 3750);
PAINT MONO (1425 3750);
DISPLAY INVISIBLE (1425 3750);
FORCEPROP 1 LAST BODY_TYPE PLUMBING
J 0
(1425 3800);
DISPLAY 0.872340 (1425 3800);
PAINT GREEN (1425 3800);
DISPLAY INVISIBLE (1425 3800);
FORCEPROP 1 LAST HDL_TAP TRUE
J 0
(1750 3625);
DISPLAY 0.872340 (1750 3625);
DISPLAY INVISIBLE (1750 3625);
FORCEPROP 1 LAST PATH I160
J 0
(1423 3750);
DISPLAY 0.872340 (1423 3750);
PAINT GREEN (1423 3750);
DISPLAY INVISIBLE (1423 3750);
FORCEADD TAP..1
(1425 3850);
FORCEPROP 3 LASTPIN (1375 3850) SIG_NAME M_G_CPU1_SA_DQS_DN<4>
J 0
(1385 3860);
DISPLAY 0.659574 (1385 3860);
PAINT MONO (1385 3860);
DISPLAY INVISIBLE (1385 3860);
FORCEPROP 1 LASTPIN (1375 3850) BN 4
J 0
(1363 3858);
DISPLAY 0.680851 (1363 3858);
PAINT GREEN (1363 3858);
FORCEPROP 2 LAST CDS_LIB standard
J 0
(1425 3850);
PAINT MONO (1425 3850);
DISPLAY INVISIBLE (1425 3850);
FORCEPROP 1 LAST BODY_TYPE PLUMBING
J 0
(1425 3900);
DISPLAY 0.872340 (1425 3900);
PAINT GREEN (1425 3900);
DISPLAY INVISIBLE (1425 3900);
FORCEPROP 1 LAST HDL_TAP TRUE
J 0
(1750 3725);
DISPLAY 0.872340 (1750 3725);
DISPLAY INVISIBLE (1750 3725);
FORCEPROP 1 LAST PATH I161
J 0
(1423 3850);
DISPLAY 0.872340 (1423 3850);
PAINT GREEN (1423 3850);
DISPLAY INVISIBLE (1423 3850);
FORCEADD TAP..1
(1425 3950);
FORCEPROP 3 LASTPIN (1375 3950) SIG_NAME M_G_CPU1_SA_DQS_DN<5>
J 0
(1385 3960);
DISPLAY 0.659574 (1385 3960);
PAINT MONO (1385 3960);
DISPLAY INVISIBLE (1385 3960);
FORCEPROP 1 LASTPIN (1375 3950) BN 5
J 0
(1363 3958);
DISPLAY 0.680851 (1363 3958);
PAINT GREEN (1363 3958);
FORCEPROP 2 LAST CDS_LIB standard
J 0
(1425 3950);
DISPLAY INVISIBLE (1425 3950);
FORCEPROP 1 LAST BODY_TYPE PLUMBING
J 0
(1425 4000);
DISPLAY 0.872340 (1425 4000);
PAINT GREEN (1425 4000);
DISPLAY INVISIBLE (1425 4000);
FORCEPROP 1 LAST HDL_TAP TRUE
J 0
(1750 3825);
DISPLAY 0.872340 (1750 3825);
DISPLAY INVISIBLE (1750 3825);
FORCEPROP 1 LAST PATH I162
J 0
(1423 3950);
DISPLAY 0.872340 (1423 3950);
PAINT GREEN (1423 3950);
DISPLAY INVISIBLE (1423 3950);
FORCEADD TAP..1
(1425 4050);
FORCEPROP 3 LASTPIN (1375 4050) SIG_NAME M_G_CPU1_SA_DQS_DN<6>
J 0
(1385 4060);
DISPLAY 0.659574 (1385 4060);
PAINT MONO (1385 4060);
DISPLAY INVISIBLE (1385 4060);
FORCEPROP 1 LASTPIN (1375 4050) BN 6
J 0
(1363 4058);
DISPLAY 0.680851 (1363 4058);
PAINT GREEN (1363 4058);
FORCEPROP 2 LAST CDS_LIB standard
J 0
(1425 4050);
DISPLAY INVISIBLE (1425 4050);
FORCEPROP 1 LAST BODY_TYPE PLUMBING
J 0
(1425 4100);
DISPLAY 0.872340 (1425 4100);
PAINT GREEN (1425 4100);
DISPLAY INVISIBLE (1425 4100);
FORCEPROP 1 LAST HDL_TAP TRUE
J 0
(1750 3925);
DISPLAY 0.872340 (1750 3925);
DISPLAY INVISIBLE (1750 3925);
FORCEPROP 1 LAST PATH I163
J 0
(1423 4050);
DISPLAY 0.872340 (1423 4050);
PAINT GREEN (1423 4050);
DISPLAY INVISIBLE (1423 4050);
FORCEADD TAP..1
(1250 4200);
FORCEPROP 3 LASTPIN (1200 4200) SIG_NAME M_G_CPU1_SA_DQS_DP<7>
J 0
(1210 4210);
DISPLAY 0.659574 (1210 4210);
PAINT MONO (1210 4210);
DISPLAY INVISIBLE (1210 4210);
FORCEPROP 1 LASTPIN (1200 4200) BN 7
J 0
(1188 4208);
DISPLAY 0.680851 (1188 4208);
PAINT GREEN (1188 4208);
FORCEPROP 2 LAST CDS_LIB standard
J 0
(1250 4200);
DISPLAY INVISIBLE (1250 4200);
FORCEPROP 1 LAST BODY_TYPE PLUMBING
J 0
(1250 4250);
DISPLAY 0.872340 (1250 4250);
PAINT GREEN (1250 4250);
DISPLAY INVISIBLE (1250 4250);
FORCEPROP 1 LAST HDL_TAP TRUE
J 0
(1575 4075);
DISPLAY 0.872340 (1575 4075);
DISPLAY INVISIBLE (1575 4075);
FORCEPROP 1 LAST PATH I164
J 0
(1248 4200);
DISPLAY 0.872340 (1248 4200);
PAINT GREEN (1248 4200);
DISPLAY INVISIBLE (1248 4200);
FORCEADD TAP..1
(1250 4300);
FORCEPROP 3 LASTPIN (1200 4300) SIG_NAME M_G_CPU1_SA_DQS_DP<8>
J 0
(1210 4310);
DISPLAY 0.659574 (1210 4310);
PAINT MONO (1210 4310);
DISPLAY INVISIBLE (1210 4310);
FORCEPROP 1 LASTPIN (1200 4300) BN 8
J 0
(1188 4308);
DISPLAY 0.680851 (1188 4308);
PAINT GREEN (1188 4308);
FORCEPROP 2 LAST CDS_LIB standard
J 0
(1250 4300);
DISPLAY INVISIBLE (1250 4300);
FORCEPROP 1 LAST BODY_TYPE PLUMBING
J 0
(1250 4350);
DISPLAY 0.872340 (1250 4350);
PAINT GREEN (1250 4350);
DISPLAY INVISIBLE (1250 4350);
FORCEPROP 1 LAST HDL_TAP TRUE
J 0
(1575 4175);
DISPLAY 0.872340 (1575 4175);
DISPLAY INVISIBLE (1575 4175);
FORCEPROP 1 LAST PATH I165
J 0
(1248 4300);
DISPLAY 0.872340 (1248 4300);
PAINT GREEN (1248 4300);
DISPLAY INVISIBLE (1248 4300);
FORCEADD TAP..1
(1250 4400);
FORCEPROP 3 LASTPIN (1200 4400) SIG_NAME M_G_CPU1_SA_DQS_DP<9>
J 0
(1210 4410);
DISPLAY 0.659574 (1210 4410);
PAINT MONO (1210 4410);
DISPLAY INVISIBLE (1210 4410);
FORCEPROP 1 LASTPIN (1200 4400) BN 9
J 0
(1188 4408);
DISPLAY 0.680851 (1188 4408);
PAINT GREEN (1188 4408);
FORCEPROP 2 LAST CDS_LIB standard
J 0
(1250 4400);
DISPLAY INVISIBLE (1250 4400);
FORCEPROP 1 LAST BODY_TYPE PLUMBING
J 0
(1250 4450);
DISPLAY 0.872340 (1250 4450);
PAINT GREEN (1250 4450);
DISPLAY INVISIBLE (1250 4450);
FORCEPROP 1 LAST HDL_TAP TRUE
J 0
(1575 4275);
DISPLAY 0.872340 (1575 4275);
DISPLAY INVISIBLE (1575 4275);
FORCEPROP 1 LAST PATH I166
J 0
(1248 4400);
DISPLAY 0.872340 (1248 4400);
PAINT GREEN (1248 4400);
DISPLAY INVISIBLE (1248 4400);
FORCEADD TAP..1
(1425 4150);
FORCEPROP 3 LASTPIN (1375 4150) SIG_NAME M_G_CPU1_SA_DQS_DN<7>
J 0
(1385 4160);
DISPLAY 0.659574 (1385 4160);
PAINT MONO (1385 4160);
DISPLAY INVISIBLE (1385 4160);
FORCEPROP 1 LASTPIN (1375 4150) BN 7
J 0
(1363 4158);
DISPLAY 0.680851 (1363 4158);
PAINT GREEN (1363 4158);
FORCEPROP 2 LAST CDS_LIB standard
J 0
(1425 4150);
DISPLAY INVISIBLE (1425 4150);
FORCEPROP 1 LAST BODY_TYPE PLUMBING
J 0
(1425 4200);
DISPLAY 0.872340 (1425 4200);
PAINT GREEN (1425 4200);
DISPLAY INVISIBLE (1425 4200);
FORCEPROP 1 LAST HDL_TAP TRUE
J 0
(1750 4025);
DISPLAY 0.872340 (1750 4025);
DISPLAY INVISIBLE (1750 4025);
FORCEPROP 1 LAST PATH I167
J 0
(1423 4150);
DISPLAY 0.872340 (1423 4150);
PAINT GREEN (1423 4150);
DISPLAY INVISIBLE (1423 4150);
FORCEADD TAP..1
(1425 4250);
FORCEPROP 3 LASTPIN (1375 4250) SIG_NAME M_G_CPU1_SA_DQS_DN<8>
J 0
(1385 4260);
DISPLAY 0.659574 (1385 4260);
PAINT MONO (1385 4260);
DISPLAY INVISIBLE (1385 4260);
FORCEPROP 1 LASTPIN (1375 4250) BN 8
J 0
(1363 4258);
DISPLAY 0.680851 (1363 4258);
PAINT GREEN (1363 4258);
FORCEPROP 2 LAST CDS_LIB standard
J 0
(1425 4250);
DISPLAY INVISIBLE (1425 4250);
FORCEPROP 1 LAST BODY_TYPE PLUMBING
J 0
(1425 4300);
DISPLAY 0.872340 (1425 4300);
PAINT GREEN (1425 4300);
DISPLAY INVISIBLE (1425 4300);
FORCEPROP 1 LAST HDL_TAP TRUE
J 0
(1750 4125);
DISPLAY 0.872340 (1750 4125);
DISPLAY INVISIBLE (1750 4125);
FORCEPROP 1 LAST PATH I168
J 0
(1423 4250);
DISPLAY 0.872340 (1423 4250);
PAINT GREEN (1423 4250);
DISPLAY INVISIBLE (1423 4250);
FORCEADD TAP..1
(1425 4350);
FORCEPROP 3 LASTPIN (1375 4350) SIG_NAME M_G_CPU1_SA_DQS_DN<9>
J 0
(1385 4360);
DISPLAY 0.659574 (1385 4360);
PAINT MONO (1385 4360);
DISPLAY INVISIBLE (1385 4360);
FORCEPROP 1 LASTPIN (1375 4350) BN 9
J 0
(1363 4358);
DISPLAY 0.680851 (1363 4358);
PAINT GREEN (1363 4358);
FORCEPROP 2 LAST CDS_LIB standard
J 0
(1425 4350);
DISPLAY INVISIBLE (1425 4350);
FORCEPROP 1 LAST BODY_TYPE PLUMBING
J 0
(1425 4400);
DISPLAY 0.872340 (1425 4400);
PAINT GREEN (1425 4400);
DISPLAY INVISIBLE (1425 4400);
FORCEPROP 1 LAST HDL_TAP TRUE
J 0
(1750 4225);
DISPLAY 0.872340 (1750 4225);
DISPLAY INVISIBLE (1750 4225);
FORCEPROP 1 LAST PATH I169
J 0
(1423 4350);
DISPLAY 0.872340 (1423 4350);
PAINT GREEN (1423 4350);
DISPLAY INVISIBLE (1423 4350);
FORCEADD OFFPAGE..1
(-4075 3600);
FORCEPROP 2 LAST $XR1 110 
J 0
(-4416 3600);
DISPLAY 0.638298 (-4416 3600);
PAINT MONO (-4416 3600);
FORCEPROP 2 LAST $XR0 57 
J 0
(-4296 3600);
DISPLAY 0.638298 (-4296 3600);
PAINT MONO (-4296 3600);
FORCEPROP 2 LAST CDS_LIB standard
J 0
(-4075 3600);
PAINT MONO (-4075 3600);
DISPLAY INVISIBLE (-4075 3600);
FORCEPROP 1 LAST OFFPAGE TRUE
J 0
(-3750 3475);
DISPLAY 0.872340 (-3750 3475);
DISPLAY INVISIBLE (-3750 3475);
FORCEPROP 1 LAST COMMENT_BODY TRUE
J 0
(-3950 3500);
DISPLAY 0.872340 (-3950 3500);
PAINT GREEN (-3950 3500);
DISPLAY INVISIBLE (-3950 3500);
FORCEPROP 2 LAST PATH I17
J 0
(-4025 3675);
DISPLAY 1.021277 (-4025 3675);
DISPLAY INVISIBLE (-4025 3675);
FORCEADD OFFPAGE..2
(2375 3325);
FORCEPROP 2 LAST $XR1 110 
J 0
(2654 3325);
DISPLAY 0.638298 (2654 3325);
PAINT MONO (2654 3325);
FORCEPROP 2 LAST $XR0 57 
J 0
(2564 3325);
DISPLAY 0.638298 (2564 3325);
PAINT MONO (2564 3325);
FORCEPROP 2 LAST CDS_LIB standard
J 0
(2375 3325);
PAINT MONO (2375 3325);
DISPLAY INVISIBLE (2375 3325);
FORCEPROP 1 LAST OFFPAGE TRUE
J 0
(2700 3200);
DISPLAY 1.170213 (2700 3200);
PAINT GREEN (2700 3200);
DISPLAY INVISIBLE (2700 3200);
FORCEPROP 1 LAST COMMENT_BODY TRUE
J 0
(2330 3230);
DISPLAY 1.170213 (2330 3230);
PAINT GREEN (2330 3230);
DISPLAY INVISIBLE (2330 3230);
FORCEPROP 2 LAST PATH I170
J 0
(2550 3400);
DISPLAY 1.021277 (2550 3400);
DISPLAY INVISIBLE (2550 3400);
FORCEADD OFFPAGE..2
(2375 3375);
FORCEPROP 2 LAST $XR1 110 
J 0
(2654 3375);
DISPLAY 0.638298 (2654 3375);
PAINT MONO (2654 3375);
FORCEPROP 2 LAST $XR0 57 
J 0
(2564 3375);
DISPLAY 0.638298 (2564 3375);
PAINT MONO (2564 3375);
FORCEPROP 2 LAST CDS_LIB standard
J 0
(2375 3375);
PAINT MONO (2375 3375);
DISPLAY INVISIBLE (2375 3375);
FORCEPROP 1 LAST OFFPAGE TRUE
J 0
(2700 3250);
DISPLAY 1.170213 (2700 3250);
PAINT GREEN (2700 3250);
DISPLAY INVISIBLE (2700 3250);
FORCEPROP 1 LAST COMMENT_BODY TRUE
J 0
(2330 3280);
DISPLAY 1.170213 (2330 3280);
PAINT GREEN (2330 3280);
DISPLAY INVISIBLE (2330 3280);
FORCEPROP 2 LAST PATH I171
J 0
(2550 3450);
DISPLAY 1.021277 (2550 3450);
DISPLAY INVISIBLE (2550 3450);
FORCEADD OFFPAGE..2
(2375 4375);
FORCEPROP 2 LAST $XR1 110 
J 0
(2654 4375);
DISPLAY 0.638298 (2654 4375);
PAINT MONO (2654 4375);
FORCEPROP 2 LAST $XR0 57 
J 0
(2564 4375);
DISPLAY 0.638298 (2564 4375);
PAINT MONO (2564 4375);
FORCEPROP 2 LAST CDS_LIB standard
J 0
(2375 4375);
PAINT MONO (2375 4375);
DISPLAY INVISIBLE (2375 4375);
FORCEPROP 1 LAST OFFPAGE TRUE
J 0
(2700 4250);
DISPLAY 1.170213 (2700 4250);
PAINT GREEN (2700 4250);
DISPLAY INVISIBLE (2700 4250);
FORCEPROP 1 LAST COMMENT_BODY TRUE
J 0
(2330 4280);
DISPLAY 1.170213 (2330 4280);
PAINT GREEN (2330 4280);
DISPLAY INVISIBLE (2330 4280);
FORCEPROP 2 LAST PATH I172
J 0
(2550 4450);
DISPLAY 1.021277 (2550 4450);
DISPLAY INVISIBLE (2550 4450);
FORCEADD OFFPAGE..2
(2375 4425);
FORCEPROP 2 LAST $XR1 110 
J 0
(2654 4425);
DISPLAY 0.638298 (2654 4425);
PAINT MONO (2654 4425);
FORCEPROP 2 LAST $XR0 57 
J 0
(2564 4425);
DISPLAY 0.638298 (2564 4425);
PAINT MONO (2564 4425);
FORCEPROP 2 LAST CDS_LIB standard
J 0
(2375 4425);
PAINT MONO (2375 4425);
DISPLAY INVISIBLE (2375 4425);
FORCEPROP 1 LAST OFFPAGE TRUE
J 0
(2700 4300);
DISPLAY 1.170213 (2700 4300);
PAINT GREEN (2700 4300);
DISPLAY INVISIBLE (2700 4300);
FORCEPROP 1 LAST COMMENT_BODY TRUE
J 0
(2330 4330);
DISPLAY 1.170213 (2330 4330);
PAINT GREEN (2330 4330);
DISPLAY INVISIBLE (2330 4330);
FORCEPROP 2 LAST PATH I173
J 0
(2550 4500);
DISPLAY 1.021277 (2550 4500);
DISPLAY INVISIBLE (2550 4500);
FORCEADD VCC_CORE..1
(2925 4950);
FORCEPROP 3 LASTPIN (2925 4900) SIG_NAME P12V_S3_AUX_CPU1_NVDIMM\g
J 0
(2935 4910);
DISPLAY 0.659574 (2935 4910);
PAINT MONO (2935 4910);
DISPLAY INVISIBLE (2935 4910);
FORCEPROP 1 LAST HDL_POWER P12V_S3_AUX_CPU1_NVDIMM
J 1
(2925 5000);
DISPLAY 1.148936 (2925 5000);
PAINT GREEN (2925 5000);
FORCEPROP 2 LAST CDS_LIB logical_power
J 0
(2925 4950);
PAINT MONO (2925 4950);
DISPLAY INVISIBLE (2925 4950);
FORCEPROP 1 LAST PATH I174
J 0
(2975 4975);
DISPLAY 0.872340 (2975 4975);
PAINT AQUA (2975 4975);
DISPLAY INVISIBLE (2975 4975);
FORCEADD OFFPAGE..1
(-4075 3300);
FORCEPROP 2 LAST $XR0 57 
J 0
(-4296 3300);
DISPLAY 0.638298 (-4296 3300);
PAINT MONO (-4296 3300);
FORCEPROP 2 LAST CDS_LIB standard
J 0
(-4075 3300);
PAINT MONO (-4075 3300);
DISPLAY INVISIBLE (-4075 3300);
FORCEPROP 1 LAST OFFPAGE TRUE
J 0
(-3750 3175);
DISPLAY 0.872340 (-3750 3175);
DISPLAY INVISIBLE (-3750 3175);
FORCEPROP 1 LAST COMMENT_BODY TRUE
J 0
(-3950 3200);
DISPLAY 0.872340 (-3950 3200);
PAINT GREEN (-3950 3200);
DISPLAY INVISIBLE (-3950 3200);
FORCEPROP 2 LAST PATH I175
J 0
(-4025 3375);
DISPLAY 1.021277 (-4025 3375);
DISPLAY INVISIBLE (-4025 3375);
FORCEADD OFFPAGE..1
(-4075 3250);
FORCEPROP 2 LAST $XR0 57 
J 0
(-4296 3250);
DISPLAY 0.638298 (-4296 3250);
PAINT MONO (-4296 3250);
FORCEPROP 2 LAST CDS_LIB standard
J 0
(-4075 3250);
PAINT MONO (-4075 3250);
DISPLAY INVISIBLE (-4075 3250);
FORCEPROP 1 LAST OFFPAGE TRUE
J 0
(-3750 3125);
DISPLAY 0.872340 (-3750 3125);
DISPLAY INVISIBLE (-3750 3125);
FORCEPROP 1 LAST COMMENT_BODY TRUE
J 0
(-3950 3150);
DISPLAY 0.872340 (-3950 3150);
PAINT GREEN (-3950 3150);
DISPLAY INVISIBLE (-3950 3150);
FORCEPROP 2 LAST PATH I176
J 0
(-4025 3325);
DISPLAY 1.021277 (-4025 3325);
DISPLAY INVISIBLE (-4025 3325);
FORCEADD SCONN288_ADR50017P087CC..3
(3775 2775);
FORCEPROP 1 LAST PART_NUMBER DFHST8FS460
J 0
(3320 4699);
DISPLAY 0.723404 (3320 4699);
PAINT GREEN (3320 4699);
DISPLAY INVISIBLE (3320 4699);
FORCEPROP 1 LAST MATERIAL IO
J 0
(3320 4572);
DISPLAY 0.723404 (3320 4572);
PAINT GREEN (3320 4572);
FORCEPROP 2 LAST PART_TYPE SMLF
J 0
(3325 4850);
DISPLAY 1.021277 (3325 4850);
FORCEPROP 2 LAST VALUE SCONN288_ADR50017-P087CC
J 0
(3325 4800);
DISPLAY 1.021277 (3325 4800);
FORCEPROP 1 LAST $LOCATION J30
J 0
(3325 4750);
DISPLAY 0.723404 (3325 4750);
PAINT GREEN (3325 4750);
FORCEPROP 0 LASTPIN (4375 1150) $PN G1
J 0
(4385 1160);
DISPLAY 0.680851 (4385 1160);
PAINT MONO (4385 1160);
FORCEPROP 0 LASTPIN (4375 1100) $PN G2
J 0
(4385 1110);
DISPLAY 0.680851 (4385 1110);
PAINT MONO (4385 1110);
FORCEPROP 0 LASTPIN (4375 1050) $PN G3
J 0
(4385 1060);
DISPLAY 0.680851 (4385 1060);
PAINT MONO (4385 1060);
FORCEPROP 0 LASTPIN (3175 4300) $PN 1
J 2
(3165 4310);
DISPLAY 0.680851 (3165 4310);
PAINT MONO (3165 4310);
FORCEPROP 0 LASTPIN (3175 4350) $PN 145
J 2
(3165 4360);
DISPLAY 0.680851 (3165 4360);
PAINT MONO (3165 4360);
FORCEPROP 0 LASTPIN (3175 4400) $PN 146
J 2
(3165 4410);
DISPLAY 0.680851 (3165 4410);
PAINT MONO (3165 4410);
FORCEPROP 0 LASTPIN (4375 1250) $PN 6
J 0
(4385 1260);
DISPLAY 0.680851 (4385 1260);
PAINT MONO (4385 1260);
FORCEPROP 0 LASTPIN (4375 1300) $PN 8
J 0
(4385 1310);
DISPLAY 0.680851 (4385 1310);
PAINT MONO (4385 1310);
FORCEPROP 0 LASTPIN (4375 1350) $PN 10
J 0
(4385 1360);
DISPLAY 0.680851 (4385 1360);
PAINT MONO (4385 1360);
FORCEPROP 0 LASTPIN (4375 1400) $PN 13
J 0
(4385 1410);
DISPLAY 0.680851 (4385 1410);
PAINT MONO (4385 1410);
FORCEPROP 0 LASTPIN (4375 1450) $PN 15
J 0
(4385 1460);
DISPLAY 0.680851 (4385 1460);
PAINT MONO (4385 1460);
FORCEPROP 0 LASTPIN (4375 1500) $PN 17
J 0
(4385 1510);
DISPLAY 0.680851 (4385 1510);
PAINT MONO (4385 1510);
FORCEPROP 0 LASTPIN (4375 1550) $PN 19
J 0
(4385 1560);
DISPLAY 0.680851 (4385 1560);
PAINT MONO (4385 1560);
FORCEPROP 0 LASTPIN (4375 1600) $PN 21
J 0
(4385 1610);
DISPLAY 0.680851 (4385 1610);
PAINT MONO (4385 1610);
FORCEPROP 0 LASTPIN (4375 1650) $PN 24
J 0
(4385 1660);
DISPLAY 0.680851 (4385 1660);
PAINT MONO (4385 1660);
FORCEPROP 0 LASTPIN (4375 1700) $PN 26
J 0
(4385 1710);
DISPLAY 0.680851 (4385 1710);
PAINT MONO (4385 1710);
FORCEPROP 0 LASTPIN (4375 1750) $PN 28
J 0
(4385 1760);
DISPLAY 0.680851 (4385 1760);
PAINT MONO (4385 1760);
FORCEPROP 0 LASTPIN (4375 1800) $PN 30
J 0
(4385 1810);
DISPLAY 0.680851 (4385 1810);
PAINT MONO (4385 1810);
FORCEPROP 0 LASTPIN (4375 1850) $PN 32
J 0
(4385 1860);
DISPLAY 0.680851 (4385 1860);
PAINT MONO (4385 1860);
FORCEPROP 0 LASTPIN (4375 1900) $PN 35
J 0
(4385 1910);
DISPLAY 0.680851 (4385 1910);
PAINT MONO (4385 1910);
FORCEPROP 0 LASTPIN (4375 1950) $PN 37
J 0
(4385 1960);
DISPLAY 0.680851 (4385 1960);
PAINT MONO (4385 1960);
FORCEPROP 0 LASTPIN (4375 2000) $PN 39
J 0
(4385 2010);
DISPLAY 0.680851 (4385 2010);
PAINT MONO (4385 2010);
FORCEPROP 0 LASTPIN (4375 2050) $PN 41
J 0
(4385 2060);
DISPLAY 0.680851 (4385 2060);
PAINT MONO (4385 2060);
FORCEPROP 0 LASTPIN (4375 2100) $PN 43
J 0
(4385 2110);
DISPLAY 0.680851 (4385 2110);
PAINT MONO (4385 2110);
FORCEPROP 0 LASTPIN (4375 2150) $PN 46
J 0
(4385 2160);
DISPLAY 0.680851 (4385 2160);
PAINT MONO (4385 2160);
FORCEPROP 0 LASTPIN (4375 2200) $PN 48
J 0
(4385 2210);
DISPLAY 0.680851 (4385 2210);
PAINT MONO (4385 2210);
FORCEPROP 0 LASTPIN (4375 2250) $PN 50
J 0
(4385 2260);
DISPLAY 0.680851 (4385 2260);
PAINT MONO (4385 2260);
FORCEPROP 0 LASTPIN (4375 2300) $PN 52
J 0
(4385 2310);
DISPLAY 0.680851 (4385 2310);
PAINT MONO (4385 2310);
FORCEPROP 0 LASTPIN (4375 2350) $PN 54
J 0
(4385 2360);
DISPLAY 0.680851 (4385 2360);
PAINT MONO (4385 2360);
FORCEPROP 0 LASTPIN (4375 2400) $PN 57
J 0
(4385 2410);
DISPLAY 0.680851 (4385 2410);
PAINT MONO (4385 2410);
FORCEPROP 0 LASTPIN (4375 2450) $PN 59
J 0
(4385 2460);
DISPLAY 0.680851 (4385 2460);
PAINT MONO (4385 2460);
FORCEPROP 0 LASTPIN (4375 2500) $PN 61
J 0
(4385 2510);
DISPLAY 0.680851 (4385 2510);
PAINT MONO (4385 2510);
FORCEPROP 0 LASTPIN (4375 2550) $PN 63
J 0
(4385 2560);
DISPLAY 0.680851 (4385 2560);
PAINT MONO (4385 2560);
FORCEPROP 0 LASTPIN (4375 2600) $PN 65
J 0
(4385 2610);
DISPLAY 0.680851 (4385 2610);
PAINT MONO (4385 2610);
FORCEPROP 0 LASTPIN (4375 2650) $PN 67
J 0
(4385 2660);
DISPLAY 0.680851 (4385 2660);
PAINT MONO (4385 2660);
FORCEPROP 0 LASTPIN (4375 2700) $PN 69
J 0
(4385 2710);
DISPLAY 0.680851 (4385 2710);
PAINT MONO (4385 2710);
FORCEPROP 0 LASTPIN (4375 2750) $PN 71
J 0
(4385 2760);
DISPLAY 0.680851 (4385 2760);
PAINT MONO (4385 2760);
FORCEPROP 0 LASTPIN (4375 2800) $PN 73
J 0
(4385 2810);
DISPLAY 0.680851 (4385 2810);
PAINT MONO (4385 2810);
FORCEPROP 0 LASTPIN (4375 2850) $PN 75
J 0
(4385 2860);
DISPLAY 0.680851 (4385 2860);
PAINT MONO (4385 2860);
FORCEPROP 0 LASTPIN (4375 2900) $PN 77
J 0
(4385 2910);
DISPLAY 0.680851 (4385 2910);
PAINT MONO (4385 2910);
FORCEPROP 0 LASTPIN (4375 2950) $PN 79
J 0
(4385 2960);
DISPLAY 0.680851 (4385 2960);
PAINT MONO (4385 2960);
FORCEPROP 0 LASTPIN (4375 3000) $PN 81
J 0
(4385 3010);
DISPLAY 0.680851 (4385 3010);
PAINT MONO (4385 3010);
FORCEPROP 0 LASTPIN (4375 3050) $PN 83
J 0
(4385 3060);
DISPLAY 0.680851 (4385 3060);
PAINT MONO (4385 3060);
FORCEPROP 0 LASTPIN (4375 3100) $PN 85
J 0
(4385 3110);
DISPLAY 0.680851 (4385 3110);
PAINT MONO (4385 3110);
FORCEPROP 0 LASTPIN (4375 3150) $PN 88
J 0
(4385 3160);
DISPLAY 0.680851 (4385 3160);
PAINT MONO (4385 3160);
FORCEPROP 0 LASTPIN (4375 3200) $PN 90
J 0
(4385 3210);
DISPLAY 0.680851 (4385 3210);
PAINT MONO (4385 3210);
FORCEPROP 0 LASTPIN (4375 3250) $PN 92
J 0
(4385 3260);
DISPLAY 0.680851 (4385 3260);
PAINT MONO (4385 3260);
FORCEPROP 0 LASTPIN (4375 3300) $PN 95
J 0
(4385 3310);
DISPLAY 0.680851 (4385 3310);
PAINT MONO (4385 3310);
FORCEPROP 0 LASTPIN (4375 3350) $PN 97
J 0
(4385 3360);
DISPLAY 0.680851 (4385 3360);
PAINT MONO (4385 3360);
FORCEPROP 0 LASTPIN (4375 3400) $PN 99
J 0
(4385 3410);
DISPLAY 0.680851 (4385 3410);
PAINT MONO (4385 3410);
FORCEPROP 0 LASTPIN (4375 3450) $PN 101
J 0
(4385 3460);
DISPLAY 0.680851 (4385 3460);
PAINT MONO (4385 3460);
FORCEPROP 0 LASTPIN (4375 3500) $PN 103
J 0
(4385 3510);
DISPLAY 0.680851 (4385 3510);
PAINT MONO (4385 3510);
FORCEPROP 0 LASTPIN (4375 3550) $PN 106
J 0
(4385 3560);
DISPLAY 0.680851 (4385 3560);
PAINT MONO (4385 3560);
FORCEPROP 0 LASTPIN (4375 3600) $PN 108
J 0
(4385 3610);
DISPLAY 0.680851 (4385 3610);
PAINT MONO (4385 3610);
FORCEPROP 0 LASTPIN (4375 3650) $PN 110
J 0
(4385 3660);
DISPLAY 0.680851 (4385 3660);
PAINT MONO (4385 3660);
FORCEPROP 0 LASTPIN (4375 3700) $PN 112
J 0
(4385 3710);
DISPLAY 0.680851 (4385 3710);
PAINT MONO (4385 3710);
FORCEPROP 0 LASTPIN (4375 3750) $PN 114
J 0
(4385 3760);
DISPLAY 0.680851 (4385 3760);
PAINT MONO (4385 3760);
FORCEPROP 0 LASTPIN (4375 3800) $PN 117
J 0
(4385 3810);
DISPLAY 0.680851 (4385 3810);
PAINT MONO (4385 3810);
FORCEPROP 0 LASTPIN (4375 3850) $PN 119
J 0
(4385 3860);
DISPLAY 0.680851 (4385 3860);
PAINT MONO (4385 3860);
FORCEPROP 0 LASTPIN (4375 3900) $PN 121
J 0
(4385 3910);
DISPLAY 0.680851 (4385 3910);
PAINT MONO (4385 3910);
FORCEPROP 0 LASTPIN (4375 3950) $PN 123
J 0
(4385 3960);
DISPLAY 0.680851 (4385 3960);
PAINT MONO (4385 3960);
FORCEPROP 0 LASTPIN (4375 4000) $PN 125
J 0
(4385 4010);
DISPLAY 0.680851 (4385 4010);
PAINT MONO (4385 4010);
FORCEPROP 0 LASTPIN (4375 4050) $PN 128
J 0
(4385 4060);
DISPLAY 0.680851 (4385 4060);
PAINT MONO (4385 4060);
FORCEPROP 0 LASTPIN (4375 4100) $PN 130
J 0
(4385 4110);
DISPLAY 0.680851 (4385 4110);
PAINT MONO (4385 4110);
FORCEPROP 0 LASTPIN (4375 4150) $PN 132
J 0
(4385 4160);
DISPLAY 0.680851 (4385 4160);
PAINT MONO (4385 4160);
FORCEPROP 0 LASTPIN (4375 4200) $PN 134
J 0
(4385 4210);
DISPLAY 0.680851 (4385 4210);
PAINT MONO (4385 4210);
FORCEPROP 0 LASTPIN (4375 4250) $PN 136
J 0
(4385 4260);
DISPLAY 0.680851 (4385 4260);
PAINT MONO (4385 4260);
FORCEPROP 0 LASTPIN (4375 4300) $PN 139
J 0
(4385 4310);
DISPLAY 0.680851 (4385 4310);
PAINT MONO (4385 4310);
FORCEPROP 0 LASTPIN (4375 4350) $PN 141
J 0
(4385 4360);
DISPLAY 0.680851 (4385 4360);
PAINT MONO (4385 4360);
FORCEPROP 0 LASTPIN (4375 4400) $PN 143
J 0
(4385 4410);
DISPLAY 0.680851 (4385 4410);
PAINT MONO (4385 4410);
FORCEPROP 0 LASTPIN (3175 1150) $PN 151
J 2
(3165 1160);
DISPLAY 0.680851 (3165 1160);
PAINT MONO (3165 1160);
FORCEPROP 0 LASTPIN (3175 1200) $PN 153
J 2
(3165 1210);
DISPLAY 0.680851 (3165 1210);
PAINT MONO (3165 1210);
FORCEPROP 0 LASTPIN (3175 1250) $PN 155
J 2
(3165 1260);
DISPLAY 0.680851 (3165 1260);
PAINT MONO (3165 1260);
FORCEPROP 0 LASTPIN (3175 1300) $PN 158
J 2
(3165 1310);
DISPLAY 0.680851 (3165 1310);
PAINT MONO (3165 1310);
FORCEPROP 0 LASTPIN (3175 1350) $PN 160
J 2
(3165 1360);
DISPLAY 0.680851 (3165 1360);
PAINT MONO (3165 1360);
FORCEPROP 0 LASTPIN (3175 1400) $PN 162
J 2
(3165 1410);
DISPLAY 0.680851 (3165 1410);
PAINT MONO (3165 1410);
FORCEPROP 0 LASTPIN (3175 1450) $PN 164
J 2
(3165 1460);
DISPLAY 0.680851 (3165 1460);
PAINT MONO (3165 1460);
FORCEPROP 0 LASTPIN (3175 1500) $PN 166
J 2
(3165 1510);
DISPLAY 0.680851 (3165 1510);
PAINT MONO (3165 1510);
FORCEPROP 0 LASTPIN (3175 1550) $PN 169
J 2
(3165 1560);
DISPLAY 0.680851 (3165 1560);
PAINT MONO (3165 1560);
FORCEPROP 0 LASTPIN (3175 1600) $PN 171
J 2
(3165 1610);
DISPLAY 0.680851 (3165 1610);
PAINT MONO (3165 1610);
FORCEPROP 0 LASTPIN (3175 1650) $PN 173
J 2
(3165 1660);
DISPLAY 0.680851 (3165 1660);
PAINT MONO (3165 1660);
FORCEPROP 0 LASTPIN (3175 1700) $PN 175
J 2
(3165 1710);
DISPLAY 0.680851 (3165 1710);
PAINT MONO (3165 1710);
FORCEPROP 0 LASTPIN (3175 1750) $PN 177
J 2
(3165 1760);
DISPLAY 0.680851 (3165 1760);
PAINT MONO (3165 1760);
FORCEPROP 0 LASTPIN (3175 1800) $PN 180
J 2
(3165 1810);
DISPLAY 0.680851 (3165 1810);
PAINT MONO (3165 1810);
FORCEPROP 0 LASTPIN (3175 1850) $PN 182
J 2
(3165 1860);
DISPLAY 0.680851 (3165 1860);
PAINT MONO (3165 1860);
FORCEPROP 0 LASTPIN (3175 1900) $PN 184
J 2
(3165 1910);
DISPLAY 0.680851 (3165 1910);
PAINT MONO (3165 1910);
FORCEPROP 0 LASTPIN (3175 1950) $PN 186
J 2
(3165 1960);
DISPLAY 0.680851 (3165 1960);
PAINT MONO (3165 1960);
FORCEPROP 0 LASTPIN (3175 2000) $PN 188
J 2
(3165 2010);
DISPLAY 0.680851 (3165 2010);
PAINT MONO (3165 2010);
FORCEPROP 0 LASTPIN (3175 2050) $PN 191
J 2
(3165 2060);
DISPLAY 0.680851 (3165 2060);
PAINT MONO (3165 2060);
FORCEPROP 0 LASTPIN (3175 2100) $PN 193
J 2
(3165 2110);
DISPLAY 0.680851 (3165 2110);
PAINT MONO (3165 2110);
FORCEPROP 0 LASTPIN (3175 2150) $PN 195
J 2
(3165 2160);
DISPLAY 0.680851 (3165 2160);
PAINT MONO (3165 2160);
FORCEPROP 0 LASTPIN (3175 2200) $PN 197
J 2
(3165 2210);
DISPLAY 0.680851 (3165 2210);
PAINT MONO (3165 2210);
FORCEPROP 0 LASTPIN (3175 2250) $PN 199
J 2
(3165 2260);
DISPLAY 0.680851 (3165 2260);
PAINT MONO (3165 2260);
FORCEPROP 0 LASTPIN (3175 2300) $PN 202
J 2
(3165 2310);
DISPLAY 0.680851 (3165 2310);
PAINT MONO (3165 2310);
FORCEPROP 0 LASTPIN (3175 2350) $PN 204
J 2
(3165 2360);
DISPLAY 0.680851 (3165 2360);
PAINT MONO (3165 2360);
FORCEPROP 0 LASTPIN (3175 2400) $PN 206
J 2
(3165 2410);
DISPLAY 0.680851 (3165 2410);
PAINT MONO (3165 2410);
FORCEPROP 0 LASTPIN (3175 2450) $PN 208
J 2
(3165 2460);
DISPLAY 0.680851 (3165 2460);
PAINT MONO (3165 2460);
FORCEPROP 0 LASTPIN (3175 2500) $PN 210
J 2
(3165 2510);
DISPLAY 0.680851 (3165 2510);
PAINT MONO (3165 2510);
FORCEPROP 0 LASTPIN (3175 2550) $PN 212
J 2
(3165 2560);
DISPLAY 0.680851 (3165 2560);
PAINT MONO (3165 2560);
FORCEPROP 0 LASTPIN (3175 2600) $PN 214
J 2
(3165 2610);
DISPLAY 0.680851 (3165 2610);
PAINT MONO (3165 2610);
FORCEPROP 0 LASTPIN (3175 2650) $PN 216
J 2
(3165 2660);
DISPLAY 0.680851 (3165 2660);
PAINT MONO (3165 2660);
FORCEPROP 0 LASTPIN (3175 2700) $PN 219
J 2
(3165 2710);
DISPLAY 0.680851 (3165 2710);
PAINT MONO (3165 2710);
FORCEPROP 0 LASTPIN (3175 2750) $PN 222
J 2
(3165 2760);
DISPLAY 0.680851 (3165 2760);
PAINT MONO (3165 2760);
FORCEPROP 0 LASTPIN (3175 2800) $PN 224
J 2
(3165 2810);
DISPLAY 0.680851 (3165 2810);
PAINT MONO (3165 2810);
FORCEPROP 0 LASTPIN (3175 2850) $PN 226
J 2
(3165 2860);
DISPLAY 0.680851 (3165 2860);
PAINT MONO (3165 2860);
FORCEPROP 0 LASTPIN (3175 2900) $PN 228
J 2
(3165 2910);
DISPLAY 0.680851 (3165 2910);
PAINT MONO (3165 2910);
FORCEPROP 0 LASTPIN (3175 2950) $PN 230
J 2
(3165 2960);
DISPLAY 0.680851 (3165 2960);
PAINT MONO (3165 2960);
FORCEPROP 0 LASTPIN (3175 3000) $PN 233
J 2
(3165 3010);
DISPLAY 0.680851 (3165 3010);
PAINT MONO (3165 3010);
FORCEPROP 0 LASTPIN (3175 3050) $PN 235
J 2
(3165 3060);
DISPLAY 0.680851 (3165 3060);
PAINT MONO (3165 3060);
FORCEPROP 0 LASTPIN (3175 3100) $PN 237
J 2
(3165 3110);
DISPLAY 0.680851 (3165 3110);
PAINT MONO (3165 3110);
FORCEPROP 0 LASTPIN (3175 3150) $PN 240
J 2
(3165 3160);
DISPLAY 0.680851 (3165 3160);
PAINT MONO (3165 3160);
FORCEPROP 0 LASTPIN (3175 3200) $PN 242
J 2
(3165 3210);
DISPLAY 0.680851 (3165 3210);
PAINT MONO (3165 3210);
FORCEPROP 0 LASTPIN (3175 3250) $PN 244
J 2
(3165 3260);
DISPLAY 0.680851 (3165 3260);
PAINT MONO (3165 3260);
FORCEPROP 0 LASTPIN (3175 3300) $PN 246
J 2
(3165 3310);
DISPLAY 0.680851 (3165 3310);
PAINT MONO (3165 3310);
FORCEPROP 0 LASTPIN (3175 3350) $PN 248
J 2
(3165 3360);
DISPLAY 0.680851 (3165 3360);
PAINT MONO (3165 3360);
FORCEPROP 0 LASTPIN (3175 3400) $PN 251
J 2
(3165 3410);
DISPLAY 0.680851 (3165 3410);
PAINT MONO (3165 3410);
FORCEPROP 0 LASTPIN (3175 3450) $PN 253
J 2
(3165 3460);
DISPLAY 0.680851 (3165 3460);
PAINT MONO (3165 3460);
FORCEPROP 0 LASTPIN (3175 3500) $PN 255
J 2
(3165 3510);
DISPLAY 0.680851 (3165 3510);
PAINT MONO (3165 3510);
FORCEPROP 0 LASTPIN (3175 3550) $PN 257
J 2
(3165 3560);
DISPLAY 0.680851 (3165 3560);
PAINT MONO (3165 3560);
FORCEPROP 0 LASTPIN (3175 3600) $PN 259
J 2
(3165 3610);
DISPLAY 0.680851 (3165 3610);
PAINT MONO (3165 3610);
FORCEPROP 0 LASTPIN (3175 3650) $PN 262
J 2
(3165 3660);
DISPLAY 0.680851 (3165 3660);
PAINT MONO (3165 3660);
FORCEPROP 0 LASTPIN (3175 3700) $PN 264
J 2
(3165 3710);
DISPLAY 0.680851 (3165 3710);
PAINT MONO (3165 3710);
FORCEPROP 0 LASTPIN (3175 3750) $PN 266
J 2
(3165 3760);
DISPLAY 0.680851 (3165 3760);
PAINT MONO (3165 3760);
FORCEPROP 0 LASTPIN (3175 3800) $PN 268
J 2
(3165 3810);
DISPLAY 0.680851 (3165 3810);
PAINT MONO (3165 3810);
FORCEPROP 0 LASTPIN (3175 3850) $PN 270
J 2
(3165 3860);
DISPLAY 0.680851 (3165 3860);
PAINT MONO (3165 3860);
FORCEPROP 0 LASTPIN (3175 3900) $PN 273
J 2
(3165 3910);
DISPLAY 0.680851 (3165 3910);
PAINT MONO (3165 3910);
FORCEPROP 0 LASTPIN (3175 3950) $PN 275
J 2
(3165 3960);
DISPLAY 0.680851 (3165 3960);
PAINT MONO (3165 3960);
FORCEPROP 0 LASTPIN (3175 4000) $PN 277
J 2
(3165 4010);
DISPLAY 0.680851 (3165 4010);
PAINT MONO (3165 4010);
FORCEPROP 0 LASTPIN (3175 4050) $PN 279
J 2
(3165 4060);
DISPLAY 0.680851 (3165 4060);
PAINT MONO (3165 4060);
FORCEPROP 0 LASTPIN (3175 4100) $PN 281
J 2
(3165 4110);
DISPLAY 0.680851 (3165 4110);
PAINT MONO (3165 4110);
FORCEPROP 0 LASTPIN (3175 4150) $PN 284
J 2
(3165 4160);
DISPLAY 0.680851 (3165 4160);
PAINT MONO (3165 4160);
FORCEPROP 0 LASTPIN (3175 4200) $PN 286
J 2
(3165 4210);
DISPLAY 0.680851 (3165 4210);
PAINT MONO (3165 4210);
FORCEPROP 0 LASTPIN (3175 4250) $PN 288
J 2
(3165 4260);
DISPLAY 0.680851 (3165 4260);
PAINT MONO (3165 4260);
FORCEPROP 2 LAST CDS_LIB pure_quanta
J 0
(3775 2775);
DISPLAY INVISIBLE (3775 2775);
FORCEPROP 1 LAST CDS_LMAN_SYM_OUTLINE -450,1775,450,-1775
J 0
(3775 2775);
DISPLAY 0.468085 (3775 2775);
PAINT GREEN (3775 2775);
DISPLAY INVISIBLE (3775 2775);
FORCEPROP 1 LAST NEEDS_NO_SIZE TRUE
J 0
(3775 2775);
DISPLAY 0.723404 (3775 2775);
PAINT GREEN (3775 2775);
DISPLAY INVISIBLE (3775 2775);
FORCEPROP 1 LAST PATH I178
J 0
(3775 2775);
DISPLAY 0.723404 (3775 2775);
PAINT GREEN (3775 2775);
DISPLAY INVISIBLE (3775 2775);
FORCEPROP 2 LAST CDS_LOCATION J30
J 0
(3325 4900);
DISPLAY 1.021277 (3325 4900);
DISPLAY INVISIBLE (3325 4900);
FORCEPROP 0 LAST $SEC 3
J 0
(3325 4900);
DISPLAY 0.680851 (3325 4900);
PAINT MONO (3325 4900);
DISPLAY INVISIBLE (3325 4900);
FORCEPROP 2 LAST CDS_SEC 3
J 0
(3325 4900);
DISPLAY 1.021277 (3325 4900);
DISPLAY INVISIBLE (3325 4900);
FORCEADD SCONN288_ADR50017P087CC..1
(-2325 2675);
FORCEPROP 1 LAST PART_NUMBER DFHST8FS460
J 0
(-2770 4685);
DISPLAY 0.723404 (-2770 4685);
PAINT GREEN (-2770 4685);
DISPLAY INVISIBLE (-2770 4685);
FORCEPROP 2 LAST PART_TYPE SMLF
J 0
(-2775 4850);
DISPLAY 1.021277 (-2775 4850);
FORCEPROP 1 LAST MATERIAL IO
J 0
(-2770 4558);
DISPLAY 0.723404 (-2770 4558);
PAINT GREEN (-2770 4558);
FORCEPROP 2 LAST VALUE SCONN288_ADR50017-P087CC
J 0
(-2775 4800);
DISPLAY 1.021277 (-2775 4800);
FORCEPROP 1 LAST $LOCATION J30
J 0
(-2775 4725);
DISPLAY 0.723404 (-2775 4725);
PAINT GREEN (-2775 4725);
FORCEPROP 0 LASTPIN (-2925 2050) $PN 62
J 2
(-2935 2060);
DISPLAY 0.680851 (-2935 2060);
PAINT MONO (-2935 2060);
FORCEPROP 0 LASTPIN (-2925 4100) $PN 66
J 2
(-2935 4110);
DISPLAY 0.680851 (-2935 4110);
PAINT MONO (-2935 4110);
FORCEPROP 0 LASTPIN (-2925 3700) $PN 76
J 2
(-2935 3710);
DISPLAY 0.680851 (-2935 3710);
PAINT MONO (-2935 3710);
FORCEPROP 0 LASTPIN (-2925 4150) $PN 211
J 2
(-2935 4160);
DISPLAY 0.680851 (-2935 4160);
PAINT MONO (-2935 4160);
FORCEPROP 0 LASTPIN (-2925 3750) $PN 221
J 2
(-2935 3760);
DISPLAY 0.680851 (-2935 3760);
PAINT MONO (-2935 3760);
FORCEPROP 0 LASTPIN (-2925 4200) $PN 68
J 2
(-2935 4210);
DISPLAY 0.680851 (-2935 4210);
PAINT MONO (-2935 4210);
FORCEPROP 0 LASTPIN (-2925 3800) $PN 78
J 2
(-2935 3810);
DISPLAY 0.680851 (-2935 3810);
PAINT MONO (-2935 3810);
FORCEPROP 0 LASTPIN (-2925 4250) $PN 213
J 2
(-2935 4260);
DISPLAY 0.680851 (-2935 4260);
PAINT MONO (-2935 4260);
FORCEPROP 0 LASTPIN (-2925 3850) $PN 223
J 2
(-2935 3860);
DISPLAY 0.680851 (-2935 3860);
PAINT MONO (-2935 3860);
FORCEPROP 0 LASTPIN (-2925 4300) $PN 70
J 2
(-2935 4310);
DISPLAY 0.680851 (-2935 4310);
PAINT MONO (-2935 4310);
FORCEPROP 0 LASTPIN (-2925 3900) $PN 80
J 2
(-2935 3910);
DISPLAY 0.680851 (-2935 3910);
PAINT MONO (-2935 3910);
FORCEPROP 0 LASTPIN (-2925 4350) $PN 215
J 2
(-2935 4360);
DISPLAY 0.680851 (-2935 4360);
PAINT MONO (-2935 4360);
FORCEPROP 0 LASTPIN (-2925 3950) $PN 225
J 2
(-2935 3960);
DISPLAY 0.680851 (-2935 3960);
PAINT MONO (-2935 3960);
FORCEPROP 0 LASTPIN (-2925 4400) $PN 72
J 2
(-2935 4410);
DISPLAY 0.680851 (-2935 4410);
PAINT MONO (-2935 4410);
FORCEPROP 0 LASTPIN (-2925 4000) $PN 82
J 2
(-2935 4010);
DISPLAY 0.680851 (-2935 4010);
PAINT MONO (-2935 4010);
FORCEPROP 0 LASTPIN (-2925 2650) $PN 51
J 2
(-2935 2660);
DISPLAY 0.680851 (-2935 2660);
PAINT MONO (-2935 2660);
FORCEPROP 0 LASTPIN (-2925 2200) $PN 96
J 2
(-2935 2210);
DISPLAY 0.680851 (-2935 2210);
PAINT MONO (-2935 2210);
FORCEPROP 0 LASTPIN (-2925 2700) $PN 53
J 2
(-2935 2710);
DISPLAY 0.680851 (-2935 2710);
PAINT MONO (-2935 2710);
FORCEPROP 0 LASTPIN (-2925 2250) $PN 98
J 2
(-2935 2260);
DISPLAY 0.680851 (-2935 2260);
PAINT MONO (-2935 2260);
FORCEPROP 0 LASTPIN (-2925 2750) $PN 196
J 2
(-2935 2760);
DISPLAY 0.680851 (-2935 2760);
PAINT MONO (-2935 2760);
FORCEPROP 0 LASTPIN (-2925 2300) $PN 241
J 2
(-2935 2310);
DISPLAY 0.680851 (-2935 2310);
PAINT MONO (-2935 2310);
FORCEPROP 0 LASTPIN (-2925 2800) $PN 198
J 2
(-2935 2810);
DISPLAY 0.680851 (-2935 2810);
PAINT MONO (-2935 2810);
FORCEPROP 0 LASTPIN (-2925 2350) $PN 243
J 2
(-2935 2360);
DISPLAY 0.680851 (-2935 2360);
PAINT MONO (-2935 2360);
FORCEPROP 0 LASTPIN (-2925 2850) $PN 58
J 2
(-2935 2860);
DISPLAY 0.680851 (-2935 2860);
PAINT MONO (-2935 2860);
FORCEPROP 0 LASTPIN (-2925 2400) $PN 89
J 2
(-2935 2410);
DISPLAY 0.680851 (-2935 2410);
PAINT MONO (-2935 2410);
FORCEPROP 0 LASTPIN (-2925 2900) $PN 60
J 2
(-2935 2910);
DISPLAY 0.680851 (-2935 2910);
PAINT MONO (-2935 2910);
FORCEPROP 0 LASTPIN (-2925 2450) $PN 91
J 2
(-2935 2460);
DISPLAY 0.680851 (-2935 2460);
PAINT MONO (-2935 2460);
FORCEPROP 0 LASTPIN (-2925 2950) $PN 203
J 2
(-2935 2960);
DISPLAY 0.680851 (-2935 2960);
PAINT MONO (-2935 2960);
FORCEPROP 0 LASTPIN (-2925 2500) $PN 234
J 2
(-2935 2510);
DISPLAY 0.680851 (-2935 2510);
PAINT MONO (-2935 2510);
FORCEPROP 0 LASTPIN (-2925 3000) $PN 205
J 2
(-2935 3010);
DISPLAY 0.680851 (-2935 3010);
PAINT MONO (-2935 3010);
FORCEPROP 0 LASTPIN (-2925 2550) $PN 236
J 2
(-2935 2560);
DISPLAY 0.680851 (-2935 2560);
PAINT MONO (-2935 2560);
FORCEPROP 0 LASTPIN (-2925 3100) $PN 218
J 2
(-2935 3110);
DISPLAY 0.680851 (-2935 3110);
PAINT MONO (-2935 3110);
FORCEPROP 0 LASTPIN (-2925 3150) $PN 217
J 2
(-2935 3160);
DISPLAY 0.680851 (-2935 3160);
PAINT MONO (-2935 3160);
FORCEPROP 0 LASTPIN (-2925 3400) $PN 64
J 2
(-2935 3410);
DISPLAY 0.680851 (-2935 3410);
PAINT MONO (-2935 3410);
FORCEPROP 0 LASTPIN (-2925 3250) $PN 84
J 2
(-2935 3260);
DISPLAY 0.680851 (-2935 3260);
PAINT MONO (-2935 3260);
FORCEPROP 0 LASTPIN (-2925 3450) $PN 209
J 2
(-2935 3460);
DISPLAY 0.680851 (-2935 3460);
PAINT MONO (-2935 3460);
FORCEPROP 0 LASTPIN (-2925 3300) $PN 229
J 2
(-2935 3310);
DISPLAY 0.680851 (-2935 3310);
PAINT MONO (-2935 3310);
FORCEPROP 0 LASTPIN (-1725 2850) $PN 7
J 0
(-1715 2860);
DISPLAY 0.680851 (-1715 2860);
PAINT MONO (-1715 2860);
FORCEPROP 0 LASTPIN (-1725 1200) $PN 100
J 0
(-1715 1210);
DISPLAY 0.680851 (-1715 1210);
PAINT MONO (-1715 1210);
FORCEPROP 0 LASTPIN (-1725 2900) $PN 9
J 0
(-1715 2910);
DISPLAY 0.680851 (-1715 2910);
PAINT MONO (-1715 2910);
FORCEPROP 0 LASTPIN (-1725 1250) $PN 102
J 0
(-1715 1260);
DISPLAY 0.680851 (-1715 1260);
PAINT MONO (-1715 1260);
FORCEPROP 0 LASTPIN (-1725 2950) $PN 152
J 0
(-1715 2960);
DISPLAY 0.680851 (-1715 2960);
PAINT MONO (-1715 2960);
FORCEPROP 0 LASTPIN (-1725 1300) $PN 245
J 0
(-1715 1310);
DISPLAY 0.680851 (-1715 1310);
PAINT MONO (-1715 1310);
FORCEPROP 0 LASTPIN (-1725 3000) $PN 154
J 0
(-1715 3010);
DISPLAY 0.680851 (-1715 3010);
PAINT MONO (-1715 3010);
FORCEPROP 0 LASTPIN (-1725 1350) $PN 247
J 0
(-1715 1360);
DISPLAY 0.680851 (-1715 1360);
PAINT MONO (-1715 1360);
FORCEPROP 0 LASTPIN (-1725 3050) $PN 14
J 0
(-1715 3060);
DISPLAY 0.680851 (-1715 3060);
PAINT MONO (-1715 3060);
FORCEPROP 0 LASTPIN (-1725 1400) $PN 107
J 0
(-1715 1410);
DISPLAY 0.680851 (-1715 1410);
PAINT MONO (-1715 1410);
FORCEPROP 0 LASTPIN (-1725 3100) $PN 16
J 0
(-1715 3110);
DISPLAY 0.680851 (-1715 3110);
PAINT MONO (-1715 3110);
FORCEPROP 0 LASTPIN (-1725 1450) $PN 109
J 0
(-1715 1460);
DISPLAY 0.680851 (-1715 1460);
PAINT MONO (-1715 1460);
FORCEPROP 0 LASTPIN (-1725 3150) $PN 159
J 0
(-1715 3160);
DISPLAY 0.680851 (-1715 3160);
PAINT MONO (-1715 3160);
FORCEPROP 0 LASTPIN (-1725 1500) $PN 252
J 0
(-1715 1510);
DISPLAY 0.680851 (-1715 1510);
PAINT MONO (-1715 1510);
FORCEPROP 0 LASTPIN (-1725 3200) $PN 161
J 0
(-1715 3210);
DISPLAY 0.680851 (-1715 3210);
PAINT MONO (-1715 3210);
FORCEPROP 0 LASTPIN (-1725 1550) $PN 254
J 0
(-1715 1560);
DISPLAY 0.680851 (-1715 1560);
PAINT MONO (-1715 1560);
FORCEPROP 0 LASTPIN (-1725 3250) $PN 18
J 0
(-1715 3260);
DISPLAY 0.680851 (-1715 3260);
PAINT MONO (-1715 3260);
FORCEPROP 0 LASTPIN (-1725 1600) $PN 111
J 0
(-1715 1610);
DISPLAY 0.680851 (-1715 1610);
PAINT MONO (-1715 1610);
FORCEPROP 0 LASTPIN (-1725 3300) $PN 20
J 0
(-1715 3310);
DISPLAY 0.680851 (-1715 3310);
PAINT MONO (-1715 3310);
FORCEPROP 0 LASTPIN (-1725 1650) $PN 113
J 0
(-1715 1660);
DISPLAY 0.680851 (-1715 1660);
PAINT MONO (-1715 1660);
FORCEPROP 0 LASTPIN (-1725 3350) $PN 163
J 0
(-1715 3360);
DISPLAY 0.680851 (-1715 3360);
PAINT MONO (-1715 3360);
FORCEPROP 0 LASTPIN (-1725 1700) $PN 256
J 0
(-1715 1710);
DISPLAY 0.680851 (-1715 1710);
PAINT MONO (-1715 1710);
FORCEPROP 0 LASTPIN (-1725 3400) $PN 165
J 0
(-1715 3410);
DISPLAY 0.680851 (-1715 3410);
PAINT MONO (-1715 3410);
FORCEPROP 0 LASTPIN (-1725 1750) $PN 258
J 0
(-1715 1760);
DISPLAY 0.680851 (-1715 1760);
PAINT MONO (-1715 1760);
FORCEPROP 0 LASTPIN (-1725 3450) $PN 25
J 0
(-1715 3460);
DISPLAY 0.680851 (-1715 3460);
PAINT MONO (-1715 3460);
FORCEPROP 0 LASTPIN (-1725 1800) $PN 118
J 0
(-1715 1810);
DISPLAY 0.680851 (-1715 1810);
PAINT MONO (-1715 1810);
FORCEPROP 0 LASTPIN (-1725 3500) $PN 27
J 0
(-1715 3510);
DISPLAY 0.680851 (-1715 3510);
PAINT MONO (-1715 3510);
FORCEPROP 0 LASTPIN (-1725 1850) $PN 120
J 0
(-1715 1860);
DISPLAY 0.680851 (-1715 1860);
PAINT MONO (-1715 1860);
FORCEPROP 0 LASTPIN (-1725 3550) $PN 170
J 0
(-1715 3560);
DISPLAY 0.680851 (-1715 3560);
PAINT MONO (-1715 3560);
FORCEPROP 0 LASTPIN (-1725 1900) $PN 263
J 0
(-1715 1910);
DISPLAY 0.680851 (-1715 1910);
PAINT MONO (-1715 1910);
FORCEPROP 0 LASTPIN (-1725 3600) $PN 172
J 0
(-1715 3610);
DISPLAY 0.680851 (-1715 3610);
PAINT MONO (-1715 3610);
FORCEPROP 0 LASTPIN (-1725 1950) $PN 265
J 0
(-1715 1960);
DISPLAY 0.680851 (-1715 1960);
PAINT MONO (-1715 1960);
FORCEPROP 0 LASTPIN (-1725 3650) $PN 29
J 0
(-1715 3660);
DISPLAY 0.680851 (-1715 3660);
PAINT MONO (-1715 3660);
FORCEPROP 0 LASTPIN (-1725 2000) $PN 122
J 0
(-1715 2010);
DISPLAY 0.680851 (-1715 2010);
PAINT MONO (-1715 2010);
FORCEPROP 0 LASTPIN (-1725 3700) $PN 31
J 0
(-1715 3710);
DISPLAY 0.680851 (-1715 3710);
PAINT MONO (-1715 3710);
FORCEPROP 0 LASTPIN (-1725 2050) $PN 124
J 0
(-1715 2060);
DISPLAY 0.680851 (-1715 2060);
PAINT MONO (-1715 2060);
FORCEPROP 0 LASTPIN (-1725 3750) $PN 174
J 0
(-1715 3760);
DISPLAY 0.680851 (-1715 3760);
PAINT MONO (-1715 3760);
FORCEPROP 0 LASTPIN (-1725 2100) $PN 267
J 0
(-1715 2110);
DISPLAY 0.680851 (-1715 2110);
PAINT MONO (-1715 2110);
FORCEPROP 0 LASTPIN (-1725 3800) $PN 176
J 0
(-1715 3810);
DISPLAY 0.680851 (-1715 3810);
PAINT MONO (-1715 3810);
FORCEPROP 0 LASTPIN (-1725 2150) $PN 269
J 0
(-1715 2160);
DISPLAY 0.680851 (-1715 2160);
PAINT MONO (-1715 2160);
FORCEPROP 0 LASTPIN (-1725 3850) $PN 36
J 0
(-1715 3860);
DISPLAY 0.680851 (-1715 3860);
PAINT MONO (-1715 3860);
FORCEPROP 0 LASTPIN (-1725 2200) $PN 129
J 0
(-1715 2210);
DISPLAY 0.680851 (-1715 2210);
PAINT MONO (-1715 2210);
FORCEPROP 0 LASTPIN (-1725 3900) $PN 38
J 0
(-1715 3910);
DISPLAY 0.680851 (-1715 3910);
PAINT MONO (-1715 3910);
FORCEPROP 0 LASTPIN (-1725 2250) $PN 131
J 0
(-1715 2260);
DISPLAY 0.680851 (-1715 2260);
PAINT MONO (-1715 2260);
FORCEPROP 0 LASTPIN (-1725 3950) $PN 181
J 0
(-1715 3960);
DISPLAY 0.680851 (-1715 3960);
PAINT MONO (-1715 3960);
FORCEPROP 0 LASTPIN (-1725 2300) $PN 274
J 0
(-1715 2310);
DISPLAY 0.680851 (-1715 2310);
PAINT MONO (-1715 2310);
FORCEPROP 0 LASTPIN (-1725 4000) $PN 183
J 0
(-1715 4010);
DISPLAY 0.680851 (-1715 4010);
PAINT MONO (-1715 4010);
FORCEPROP 0 LASTPIN (-1725 2350) $PN 276
J 0
(-1715 2360);
DISPLAY 0.680851 (-1715 2360);
PAINT MONO (-1715 2360);
FORCEPROP 0 LASTPIN (-1725 4050) $PN 40
J 0
(-1715 4060);
DISPLAY 0.680851 (-1715 4060);
PAINT MONO (-1715 4060);
FORCEPROP 0 LASTPIN (-1725 2400) $PN 133
J 0
(-1715 2410);
DISPLAY 0.680851 (-1715 2410);
PAINT MONO (-1715 2410);
FORCEPROP 0 LASTPIN (-1725 4100) $PN 42
J 0
(-1715 4110);
DISPLAY 0.680851 (-1715 4110);
PAINT MONO (-1715 4110);
FORCEPROP 0 LASTPIN (-1725 2450) $PN 135
J 0
(-1715 2460);
DISPLAY 0.680851 (-1715 2460);
PAINT MONO (-1715 2460);
FORCEPROP 0 LASTPIN (-1725 4150) $PN 185
J 0
(-1715 4160);
DISPLAY 0.680851 (-1715 4160);
PAINT MONO (-1715 4160);
FORCEPROP 0 LASTPIN (-1725 2500) $PN 278
J 0
(-1715 2510);
DISPLAY 0.680851 (-1715 2510);
PAINT MONO (-1715 2510);
FORCEPROP 0 LASTPIN (-1725 4200) $PN 187
J 0
(-1715 4210);
DISPLAY 0.680851 (-1715 4210);
PAINT MONO (-1715 4210);
FORCEPROP 0 LASTPIN (-1725 2550) $PN 280
J 0
(-1715 2560);
DISPLAY 0.680851 (-1715 2560);
PAINT MONO (-1715 2560);
FORCEPROP 0 LASTPIN (-1725 4250) $PN 47
J 0
(-1715 4260);
DISPLAY 0.680851 (-1715 4260);
PAINT MONO (-1715 4260);
FORCEPROP 0 LASTPIN (-1725 2600) $PN 140
J 0
(-1715 2610);
DISPLAY 0.680851 (-1715 2610);
PAINT MONO (-1715 2610);
FORCEPROP 0 LASTPIN (-1725 4300) $PN 49
J 0
(-1715 4310);
DISPLAY 0.680851 (-1715 4310);
PAINT MONO (-1715 4310);
FORCEPROP 0 LASTPIN (-1725 2650) $PN 142
J 0
(-1715 2660);
DISPLAY 0.680851 (-1715 2660);
PAINT MONO (-1715 2660);
FORCEPROP 0 LASTPIN (-1725 4350) $PN 192
J 0
(-1715 4360);
DISPLAY 0.680851 (-1715 4360);
PAINT MONO (-1715 4360);
FORCEPROP 0 LASTPIN (-1725 2700) $PN 285
J 0
(-1715 2710);
DISPLAY 0.680851 (-1715 2710);
PAINT MONO (-1715 2710);
FORCEPROP 0 LASTPIN (-1725 4400) $PN 194
J 0
(-1715 4410);
DISPLAY 0.680851 (-1715 4410);
PAINT MONO (-1715 4410);
FORCEPROP 0 LASTPIN (-1725 2750) $PN 287
J 0
(-1715 2760);
DISPLAY 0.680851 (-1715 2760);
PAINT MONO (-1715 2760);
FORCEPROP 0 LASTPIN (-2925 1900) $PN 148
J 2
(-2935 1910);
DISPLAY 0.680851 (-2935 1910);
PAINT MONO (-2935 1910);
FORCEPROP 0 LASTPIN (-2925 1800) $PN 4
J 2
(-2935 1810);
DISPLAY 0.680851 (-2935 1810);
PAINT MONO (-2935 1810);
FORCEPROP 0 LASTPIN (-2925 1850) $PN 5
J 2
(-2935 1860);
DISPLAY 0.680851 (-2935 1860);
PAINT MONO (-2935 1860);
FORCEPROP 0 LASTPIN (-2925 1000) $PN 86
J 2
(-2935 1010);
DISPLAY 0.680851 (-2935 1010);
PAINT MONO (-2935 1010);
FORCEPROP 0 LASTPIN (-2925 950) $PN 87
J 2
(-2935 960);
DISPLAY 0.680851 (-2935 960);
PAINT MONO (-2935 960);
FORCEPROP 0 LASTPIN (-2925 3600) $PN 74
J 2
(-2935 3610);
DISPLAY 0.680851 (-2935 3610);
PAINT MONO (-2935 3610);
FORCEPROP 0 LASTPIN (-2925 3550) $PN 227
J 2
(-2935 3560);
DISPLAY 0.680851 (-2935 3560);
PAINT MONO (-2935 3560);
FORCEPROP 0 LASTPIN (-2925 1550) $PN 147
J 2
(-2935 1560);
DISPLAY 0.680851 (-2935 1560);
PAINT MONO (-2935 1560);
FORCEPROP 0 LASTPIN (-2925 2100) $PN 207
J 2
(-2935 2110);
DISPLAY 0.680851 (-2935 2110);
PAINT MONO (-2935 2110);
FORCEPROP 0 LASTPIN (-2925 1150) $PN 2
J 2
(-2935 1160);
DISPLAY 0.680851 (-2935 1160);
PAINT MONO (-2935 1160);
FORCEPROP 0 LASTPIN (-2925 1200) $PN 144
J 2
(-2935 1210);
DISPLAY 0.680851 (-2935 1210);
PAINT MONO (-2935 1210);
FORCEPROP 0 LASTPIN (-2925 1250) $PN 149
J 2
(-2935 1260);
DISPLAY 0.680851 (-2935 1260);
PAINT MONO (-2935 1260);
FORCEPROP 0 LASTPIN (-2925 1300) $PN 150
J 2
(-2935 1310);
DISPLAY 0.680851 (-2935 1310);
PAINT MONO (-2935 1310);
FORCEPROP 0 LASTPIN (-2925 1350) $PN 220
J 2
(-2935 1360);
DISPLAY 0.680851 (-2935 1360);
PAINT MONO (-2935 1360);
FORCEPROP 0 LASTPIN (-2925 1400) $PN 231
J 2
(-2935 1410);
DISPLAY 0.680851 (-2935 1410);
PAINT MONO (-2935 1410);
FORCEPROP 0 LASTPIN (-2925 1450) $PN 232
J 2
(-2935 1460);
DISPLAY 0.680851 (-2935 1460);
PAINT MONO (-2935 1460);
FORCEPROP 0 LASTPIN (-2925 1950) $PN 3
J 2
(-2935 1960);
DISPLAY 0.680851 (-2935 1960);
PAINT MONO (-2935 1960);
FORCEPROP 2 LAST CDS_LIB pure_quanta
J 0
(-2325 2675);
DISPLAY INVISIBLE (-2325 2675);
FORCEPROP 1 LAST CDS_LMAN_SYM_OUTLINE -450,1875,450,-1875
J 0
(-2325 2675);
DISPLAY 0.468085 (-2325 2675);
PAINT GREEN (-2325 2675);
DISPLAY INVISIBLE (-2325 2675);
FORCEPROP 1 LAST NEEDS_NO_SIZE TRUE
J 0
(-2325 2675);
DISPLAY 0.723404 (-2325 2675);
PAINT GREEN (-2325 2675);
DISPLAY INVISIBLE (-2325 2675);
FORCEPROP 1 LAST PATH I179
J 0
(-2325 2675);
DISPLAY 0.723404 (-2325 2675);
PAINT GREEN (-2325 2675);
DISPLAY INVISIBLE (-2325 2675);
FORCEPROP 2 LAST CDS_LOCATION J30
J 0
(-2775 4900);
DISPLAY 1.021277 (-2775 4900);
DISPLAY INVISIBLE (-2775 4900);
FORCEPROP 0 LAST $SEC 1
J 0
(-2775 4900);
DISPLAY 0.680851 (-2775 4900);
PAINT MONO (-2775 4900);
DISPLAY INVISIBLE (-2775 4900);
FORCEPROP 2 LAST CDS_SEC 1
J 0
(-2775 4900);
DISPLAY 1.021277 (-2775 4900);
DISPLAY INVISIBLE (-2775 4900);
FORCEADD OFFPAGE..1
(-4075 3550);
FORCEPROP 2 LAST $XR1 110 
J 0
(-4416 3550);
DISPLAY 0.638298 (-4416 3550);
PAINT MONO (-4416 3550);
FORCEPROP 2 LAST $XR0 57 
J 0
(-4296 3550);
DISPLAY 0.638298 (-4296 3550);
PAINT MONO (-4296 3550);
FORCEPROP 2 LAST CDS_LIB standard
J 0
(-4075 3550);
PAINT MONO (-4075 3550);
DISPLAY INVISIBLE (-4075 3550);
FORCEPROP 1 LAST OFFPAGE TRUE
J 0
(-3750 3425);
DISPLAY 0.872340 (-3750 3425);
DISPLAY INVISIBLE (-3750 3425);
FORCEPROP 1 LAST COMMENT_BODY TRUE
J 0
(-3950 3450);
DISPLAY 0.872340 (-3950 3450);
PAINT GREEN (-3950 3450);
DISPLAY INVISIBLE (-3950 3450);
FORCEPROP 2 LAST PATH I18
J 0
(-4025 3625);
DISPLAY 1.021277 (-4025 3625);
DISPLAY INVISIBLE (-4025 3625);
FORCEADD SCONN288_ADR50017P087CC..2
(350 3400);
FORCEPROP 1 LAST PART_NUMBER DFHST8FS460
J 0
(-255 4688);
DISPLAY 0.723404 (-255 4688);
PAINT GREEN (-255 4688);
DISPLAY INVISIBLE (-255 4688);
FORCEPROP 2 LAST PART_TYPE SMLF
J 0
(-250 4925);
DISPLAY 1.021277 (-250 4925);
FORCEPROP 2 LAST VALUE SCONN288_ADR50017-P087CC
J 0
(-250 4875);
DISPLAY 1.021277 (-250 4875);
FORCEPROP 1 LAST MATERIAL IO
J 0
(-255 4561);
DISPLAY 0.723404 (-255 4561);
PAINT GREEN (-255 4561);
FORCEPROP 1 LAST LOCATION J30
J 0
(-255 4835);
DISPLAY 0.723404 (-255 4835);
PAINT GREEN (-255 4835);
FORCEPROP 0 LASTPIN (1100 3450) $PN 12
J 0
(1110 3460);
DISPLAY 0.680851 (1110 3460);
PAINT MONO (1110 3460);
FORCEPROP 0 LASTPIN (1100 3500) $PN 11
J 0
(1110 3510);
DISPLAY 0.680851 (1110 3510);
PAINT MONO (1110 3510);
FORCEPROP 0 LASTPIN (1100 2400) $PN 105
J 0
(1110 2410);
DISPLAY 0.680851 (1110 2410);
PAINT MONO (1110 2410);
FORCEPROP 0 LASTPIN (1100 2450) $PN 104
J 0
(1110 2460);
DISPLAY 0.680851 (1110 2460);
PAINT MONO (1110 2460);
FORCEPROP 0 LASTPIN (1100 3550) $PN 23
J 0
(1110 3560);
DISPLAY 0.680851 (1110 3560);
PAINT MONO (1110 3560);
FORCEPROP 0 LASTPIN (1100 3600) $PN 22
J 0
(1110 3610);
DISPLAY 0.680851 (1110 3610);
PAINT MONO (1110 3610);
FORCEPROP 0 LASTPIN (1100 2500) $PN 116
J 0
(1110 2510);
DISPLAY 0.680851 (1110 2510);
PAINT MONO (1110 2510);
FORCEPROP 0 LASTPIN (1100 2550) $PN 115
J 0
(1110 2560);
DISPLAY 0.680851 (1110 2560);
PAINT MONO (1110 2560);
FORCEPROP 0 LASTPIN (1100 3650) $PN 34
J 0
(1110 3660);
DISPLAY 0.680851 (1110 3660);
PAINT MONO (1110 3660);
FORCEPROP 0 LASTPIN (1100 3700) $PN 33
J 0
(1110 3710);
DISPLAY 0.680851 (1110 3710);
PAINT MONO (1110 3710);
FORCEPROP 0 LASTPIN (1100 2600) $PN 127
J 0
(1110 2610);
DISPLAY 0.680851 (1110 2610);
PAINT MONO (1110 2610);
FORCEPROP 0 LASTPIN (1100 2650) $PN 126
J 0
(1110 2660);
DISPLAY 0.680851 (1110 2660);
PAINT MONO (1110 2660);
FORCEPROP 0 LASTPIN (1100 3750) $PN 45
J 0
(1110 3760);
DISPLAY 0.680851 (1110 3760);
PAINT MONO (1110 3760);
FORCEPROP 0 LASTPIN (1100 3800) $PN 44
J 0
(1110 3810);
DISPLAY 0.680851 (1110 3810);
PAINT MONO (1110 3810);
FORCEPROP 0 LASTPIN (1100 2700) $PN 138
J 0
(1110 2710);
DISPLAY 0.680851 (1110 2710);
PAINT MONO (1110 2710);
FORCEPROP 0 LASTPIN (1100 2750) $PN 137
J 0
(1110 2760);
DISPLAY 0.680851 (1110 2760);
PAINT MONO (1110 2760);
FORCEPROP 0 LASTPIN (1100 3850) $PN 56
J 0
(1110 3860);
DISPLAY 0.680851 (1110 3860);
PAINT MONO (1110 3860);
FORCEPROP 0 LASTPIN (1100 3900) $PN 55
J 0
(1110 3910);
DISPLAY 0.680851 (1110 3910);
PAINT MONO (1110 3910);
FORCEPROP 0 LASTPIN (1100 2800) $PN 238
J 0
(1110 2810);
DISPLAY 0.680851 (1110 2810);
PAINT MONO (1110 2810);
FORCEPROP 0 LASTPIN (1100 2850) $PN 239
J 0
(1110 2860);
DISPLAY 0.680851 (1110 2860);
PAINT MONO (1110 2860);
FORCEPROP 0 LASTPIN (1100 3950) $PN 156
J 0
(1110 3960);
DISPLAY 0.680851 (1110 3960);
PAINT MONO (1110 3960);
FORCEPROP 0 LASTPIN (1100 4000) $PN 157
J 0
(1110 4010);
DISPLAY 0.680851 (1110 4010);
PAINT MONO (1110 4010);
FORCEPROP 0 LASTPIN (1100 2900) $PN 249
J 0
(1110 2910);
DISPLAY 0.680851 (1110 2910);
PAINT MONO (1110 2910);
FORCEPROP 0 LASTPIN (1100 2950) $PN 250
J 0
(1110 2960);
DISPLAY 0.680851 (1110 2960);
PAINT MONO (1110 2960);
FORCEPROP 0 LASTPIN (1100 4050) $PN 167
J 0
(1110 4060);
DISPLAY 0.680851 (1110 4060);
PAINT MONO (1110 4060);
FORCEPROP 0 LASTPIN (1100 4100) $PN 168
J 0
(1110 4110);
DISPLAY 0.680851 (1110 4110);
PAINT MONO (1110 4110);
FORCEPROP 0 LASTPIN (1100 3000) $PN 260
J 0
(1110 3010);
DISPLAY 0.680851 (1110 3010);
PAINT MONO (1110 3010);
FORCEPROP 0 LASTPIN (1100 3050) $PN 261
J 0
(1110 3060);
DISPLAY 0.680851 (1110 3060);
PAINT MONO (1110 3060);
FORCEPROP 0 LASTPIN (1100 4150) $PN 178
J 0
(1110 4160);
DISPLAY 0.680851 (1110 4160);
PAINT MONO (1110 4160);
FORCEPROP 0 LASTPIN (1100 4200) $PN 179
J 0
(1110 4210);
DISPLAY 0.680851 (1110 4210);
PAINT MONO (1110 4210);
FORCEPROP 0 LASTPIN (1100 3100) $PN 271
J 0
(1110 3110);
DISPLAY 0.680851 (1110 3110);
PAINT MONO (1110 3110);
FORCEPROP 0 LASTPIN (1100 3150) $PN 272
J 0
(1110 3160);
DISPLAY 0.680851 (1110 3160);
PAINT MONO (1110 3160);
FORCEPROP 0 LASTPIN (1100 4250) $PN 189
J 0
(1110 4260);
DISPLAY 0.680851 (1110 4260);
PAINT MONO (1110 4260);
FORCEPROP 0 LASTPIN (1100 4300) $PN 190
J 0
(1110 4310);
DISPLAY 0.680851 (1110 4310);
PAINT MONO (1110 4310);
FORCEPROP 0 LASTPIN (1100 3200) $PN 282
J 0
(1110 3210);
DISPLAY 0.680851 (1110 3210);
PAINT MONO (1110 3210);
FORCEPROP 0 LASTPIN (1100 3250) $PN 283
J 0
(1110 3260);
DISPLAY 0.680851 (1110 3260);
PAINT MONO (1110 3260);
FORCEPROP 0 LASTPIN (1100 4350) $PN 200
J 0
(1110 4360);
DISPLAY 0.680851 (1110 4360);
PAINT MONO (1110 4360);
FORCEPROP 0 LASTPIN (1100 4400) $PN 201
J 0
(1110 4410);
DISPLAY 0.680851 (1110 4410);
PAINT MONO (1110 4410);
FORCEPROP 0 LASTPIN (1100 3300) $PN 94
J 0
(1110 3310);
DISPLAY 0.680851 (1110 3310);
PAINT MONO (1110 3310);
FORCEPROP 0 LASTPIN (1100 3350) $PN 93
J 0
(1110 3360);
DISPLAY 0.680851 (1110 3360);
PAINT MONO (1110 3360);
FORCEPROP 2 LAST CDS_LIB pure_quanta
J 0
(350 3400);
DISPLAY INVISIBLE (350 3400);
FORCEPROP 1 LAST CDS_LMAN_SYM_OUTLINE -600,1150,600,-1150
J 0
(350 3400);
DISPLAY 0.468085 (350 3400);
PAINT GREEN (350 3400);
DISPLAY INVISIBLE (350 3400);
FORCEPROP 1 LAST NEEDS_NO_SIZE TRUE
J 0
(350 3400);
DISPLAY 0.723404 (350 3400);
PAINT GREEN (350 3400);
DISPLAY INVISIBLE (350 3400);
FORCEPROP 1 LAST PATH I180
J 0
(350 3400);
DISPLAY 0.723404 (350 3400);
PAINT GREEN (350 3400);
DISPLAY INVISIBLE (350 3400);
FORCEPROP 0 LAST $SEC 2
J 0
(-250 4975);
DISPLAY 0.680851 (-250 4975);
PAINT MONO (-250 4975);
DISPLAY INVISIBLE (-250 4975);
FORCEPROP 0 LAST CDS_SEC 2
J 0
(-250 4975);
DISPLAY 1.021277 (-250 4975);
DISPLAY INVISIBLE (-250 4975);
FORCEADD OFFPAGE..1
(-2900 1625);
FORCEPROP 2 LAST $XR7 113 
J 0
(-3992 1625);
DISPLAY 0.638298 (-3992 1625);
PAINT MONO (-3992 1625);
FORCEPROP 2 LAST $XR6 112 
J 0
(-3872 1625);
DISPLAY 0.638298 (-3872 1625);
PAINT MONO (-3872 1625);
FORCEPROP 2 LAST $XR5 110 
J 0
(-3752 1625);
DISPLAY 0.638298 (-3752 1625);
PAINT MONO (-3752 1625);
FORCEPROP 2 LAST $XR4 109 
J 0
(-3632 1625);
DISPLAY 0.638298 (-3632 1625);
PAINT MONO (-3632 1625);
FORCEPROP 2 LAST $XR3 108 
J 0
(-3512 1625);
DISPLAY 0.638298 (-3512 1625);
PAINT MONO (-3512 1625);
FORCEPROP 2 LAST $XR2 107 
J 0
(-3392 1625);
DISPLAY 0.638298 (-3392 1625);
PAINT MONO (-3392 1625);
FORCEPROP 2 LAST $XR1 106 
J 0
(-3272 1625);
DISPLAY 0.638298 (-3272 1625);
PAINT MONO (-3272 1625);
FORCEPROP 2 LAST $XR0 230 
J 0
(-3152 1625);
DISPLAY 0.638298 (-3152 1625);
PAINT MONO (-3152 1625);
FORCEPROP 2 LAST CDS_LIB standard
J 2
(-2900 1625);
DISPLAY INVISIBLE (-2900 1625);
FORCEPROP 1 LAST OFFPAGE TRUE
J 0
(-2575 1500);
DISPLAY 0.872340 (-2575 1500);
DISPLAY INVISIBLE (-2575 1500);
FORCEPROP 1 LAST COMMENT_BODY TRUE
J 0
(-2775 1525);
DISPLAY 0.872340 (-2775 1525);
PAINT GREEN (-2775 1525);
DISPLAY INVISIBLE (-2775 1525);
FORCEPROP 2 LAST PATH I181
J 2
(-3075 1700);
DISPLAY 1.021277 (-3075 1700);
DISPLAY INVISIBLE (-3075 1700);
FORCEADD Q_RES..1
(-4150 1675);
FORCEPROP 1 LAST PART_NUMBER CS04992FB07
J 0
(-4050 1650);
DISPLAY 0.404255 (-4050 1650);
DISPLAY INVISIBLE (-4050 1650);
FORCEPROP 1 LAST VALUE 49.9
J 2
(-3925 1675);
DISPLAY 0.510638 (-3925 1675);
FORCEPROP 1 LAST MATERIAL CHIP
J 0
(-4350 1650);
DISPLAY 0.404255 (-4350 1650);
FORCEPROP 1 LAST $LOCATION R3904
J 0
(-4400 1675);
DISPLAY 0.638298 (-4400 1675);
FORCEPROP 1 LASTPIN (-4250 1675) $PN 1
J 0
(-4238 1687);
DISPLAY 0.787234 (-4238 1687);
PAINT MONO (-4238 1687);
FORCEPROP 1 LASTPIN (-4050 1675) $PN 2
J 0
(-4088 1687);
DISPLAY 0.787234 (-4088 1687);
PAINT MONO (-4088 1687);
FORCEPROP 2 LAST CDS_LIB pure_quanta
J 0
(-4150 1675);
DISPLAY INVISIBLE (-4150 1675);
FORCEPROP 1 LAST PACK_TYPE 0402LF
J 0
(-3850 1675);
DISPLAY 0.510638 (-3850 1675);
DISPLAY INVISIBLE (-3850 1675);
FORCEPROP 1 LAST TOLERANCE 1%
J 0
(-3925 1675);
DISPLAY 0.510638 (-3925 1675);
DISPLAY INVISIBLE (-3925 1675);
FORCEPROP 1 LAST WATTAGE 1/16W
J 2
(-3850 1625);
DISPLAY 0.404255 (-3850 1625);
DISPLAY INVISIBLE (-3850 1625);
FORCEPROP 1 LAST PATH I182
J 0
(-4200 1825);
DISPLAY 0.978723 (-4200 1825);
PAINT WHITE (-4200 1825);
DISPLAY INVISIBLE (-4200 1825);
FORCEPROP 0 LAST CDS_LOCATION R3904
J 0
(-4300 1725);
DISPLAY 1.021277 (-4300 1725);
DISPLAY INVISIBLE (-4300 1725);
FORCEPROP 0 LAST $SEC 1
J 0
(-4300 1725);
DISPLAY 0.680851 (-4300 1725);
PAINT MONO (-4300 1725);
DISPLAY INVISIBLE (-4300 1725);
FORCEPROP 0 LAST CDS_SEC 1
J 0
(-4300 1725);
DISPLAY 1.021277 (-4300 1725);
DISPLAY INVISIBLE (-4300 1725);
FORCEADD OFFPAGE..1
(-4075 3450);
FORCEPROP 2 LAST $XR0 57 
J 0
(-4296 3450);
DISPLAY 0.638298 (-4296 3450);
PAINT MONO (-4296 3450);
FORCEPROP 2 LAST CDS_LIB standard
J 0
(-4075 3450);
PAINT MONO (-4075 3450);
DISPLAY INVISIBLE (-4075 3450);
FORCEPROP 1 LAST OFFPAGE TRUE
J 0
(-3750 3325);
DISPLAY 0.872340 (-3750 3325);
DISPLAY INVISIBLE (-3750 3325);
FORCEPROP 1 LAST COMMENT_BODY TRUE
J 0
(-3950 3350);
DISPLAY 0.872340 (-3950 3350);
PAINT GREEN (-3950 3350);
DISPLAY INVISIBLE (-3950 3350);
FORCEPROP 2 LAST PATH I19
J 0
(-4025 3525);
DISPLAY 1.021277 (-4025 3525);
DISPLAY INVISIBLE (-4025 3525);
FORCEADD OFFPAGE..2
R 2
(-4075 950);
FORCEPROP 2 LAST $XR0 57 
J 0
(-4299 950);
DISPLAY 0.638298 (-4299 950);
PAINT MONO (-4299 950);
FORCEPROP 2 LAST CDS_LIB standard
J 0
(-4075 950);
PAINT MONO (-4075 950);
DISPLAY INVISIBLE (-4075 950);
FORCEPROP 1 LAST OFFPAGE TRUE
J 2
(-4400 825);
DISPLAY 0.872340 (-4400 825);
DISPLAY INVISIBLE (-4400 825);
FORCEPROP 1 LAST COMMENT_BODY TRUE
J 2
(-4030 855);
DISPLAY 0.872340 (-4030 855);
PAINT GREEN (-4030 855);
DISPLAY INVISIBLE (-4030 855);
FORCEPROP 2 LAST PATH I2
J 0
(-4025 1025);
DISPLAY 1.021277 (-4025 1025);
DISPLAY INVISIBLE (-4025 1025);
FORCEADD OFFPAGE..1
(-4075 4025);
FORCEPROP 2 LAST $XR1 110 
J 0
(-4416 4025);
DISPLAY 0.638298 (-4416 4025);
PAINT MONO (-4416 4025);
FORCEPROP 2 LAST $XR0 57 
J 0
(-4296 4025);
DISPLAY 0.638298 (-4296 4025);
PAINT MONO (-4296 4025);
FORCEPROP 2 LAST CDS_LIB standard
J 0
(-4075 4025);
PAINT MONO (-4075 4025);
DISPLAY INVISIBLE (-4075 4025);
FORCEPROP 1 LAST OFFPAGE TRUE
J 0
(-3750 3900);
DISPLAY 0.872340 (-3750 3900);
DISPLAY INVISIBLE (-3750 3900);
FORCEPROP 1 LAST COMMENT_BODY TRUE
J 0
(-3950 3925);
DISPLAY 0.872340 (-3950 3925);
PAINT GREEN (-3950 3925);
DISPLAY INVISIBLE (-3950 3925);
FORCEPROP 2 LAST PATH I20
J 0
(-4025 4100);
DISPLAY 1.021277 (-4025 4100);
DISPLAY INVISIBLE (-4025 4100);
FORCEADD OFFPAGE..1
(-4075 4425);
FORCEPROP 2 LAST $XR1 110 
J 0
(-4416 4425);
DISPLAY 0.638298 (-4416 4425);
PAINT MONO (-4416 4425);
FORCEPROP 2 LAST $XR0 57 
J 0
(-4296 4425);
DISPLAY 0.638298 (-4296 4425);
PAINT MONO (-4296 4425);
FORCEPROP 2 LAST CDS_LIB standard
J 0
(-4075 4425);
PAINT MONO (-4075 4425);
DISPLAY INVISIBLE (-4075 4425);
FORCEPROP 1 LAST OFFPAGE TRUE
J 0
(-3750 4300);
DISPLAY 0.872340 (-3750 4300);
DISPLAY INVISIBLE (-3750 4300);
FORCEPROP 1 LAST COMMENT_BODY TRUE
J 0
(-3950 4325);
DISPLAY 0.872340 (-3950 4325);
PAINT GREEN (-3950 4325);
DISPLAY INVISIBLE (-3950 4325);
FORCEPROP 2 LAST PATH I21
J 0
(-4025 4500);
DISPLAY 1.021277 (-4025 4500);
DISPLAY INVISIBLE (-4025 4500);
FORCEADD VCC_CORE..1
(-3975 2275);
FORCEPROP 3 LASTPIN (-3975 2225) SIG_NAME P3V3_AUX\g
J 0
(-3965 2235);
DISPLAY 0.659574 (-3965 2235);
PAINT MONO (-3965 2235);
DISPLAY INVISIBLE (-3965 2235);
FORCEPROP 1 LAST HDL_POWER P3V3_AUX
J 1
(-3975 2325);
DISPLAY 1.148936 (-3975 2325);
PAINT GREEN (-3975 2325);
FORCEPROP 2 LAST CDS_LIB logical_power
J 0
(-3975 2275);
PAINT MONO (-3975 2275);
DISPLAY INVISIBLE (-3975 2275);
FORCEPROP 1 LAST PATH I22
J 0
(-3925 2300);
DISPLAY 0.872340 (-3925 2300);
PAINT AQUA (-3925 2300);
DISPLAY INVISIBLE (-3925 2300);
FORCEADD TAP..1
R 2
(-3150 2200);
FORCEPROP 3 LASTPIN (-3100 2200) SIG_NAME M_G_CPU1_SB_CB<0>
J 0
(-3090 2210);
DISPLAY 0.659574 (-3090 2210);
PAINT MONO (-3090 2210);
DISPLAY INVISIBLE (-3090 2210);
FORCEPROP 1 LASTPIN (-3100 2200) BN 0
J 2
(-3088 2208);
DISPLAY 0.680851 (-3088 2208);
PAINT GREEN (-3088 2208);
FORCEPROP 2 LAST CDS_LIB standard
J 0
(-3150 2200);
PAINT MONO (-3150 2200);
DISPLAY INVISIBLE (-3150 2200);
FORCEPROP 1 LAST BODY_TYPE PLUMBING
J 2
(-3150 2250);
DISPLAY 0.872340 (-3150 2250);
PAINT GREEN (-3150 2250);
DISPLAY INVISIBLE (-3150 2250);
FORCEPROP 1 LAST HDL_TAP TRUE
J 2
(-3475 2075);
DISPLAY 0.872340 (-3475 2075);
DISPLAY INVISIBLE (-3475 2075);
FORCEPROP 1 LAST PATH I23
J 2
(-3148 2200);
DISPLAY 0.872340 (-3148 2200);
PAINT GREEN (-3148 2200);
DISPLAY INVISIBLE (-3148 2200);
FORCEADD TAP..1
R 2
(-3150 2250);
FORCEPROP 3 LASTPIN (-3100 2250) SIG_NAME M_G_CPU1_SB_CB<1>
J 0
(-3090 2260);
DISPLAY 0.659574 (-3090 2260);
PAINT MONO (-3090 2260);
DISPLAY INVISIBLE (-3090 2260);
FORCEPROP 1 LASTPIN (-3100 2250) BN 1
J 2
(-3088 2258);
DISPLAY 0.680851 (-3088 2258);
PAINT GREEN (-3088 2258);
FORCEPROP 2 LAST CDS_LIB standard
J 0
(-3150 2250);
DISPLAY INVISIBLE (-3150 2250);
FORCEPROP 1 LAST BODY_TYPE PLUMBING
J 2
(-3150 2300);
DISPLAY 0.872340 (-3150 2300);
PAINT GREEN (-3150 2300);
DISPLAY INVISIBLE (-3150 2300);
FORCEPROP 1 LAST HDL_TAP TRUE
J 2
(-3475 2125);
DISPLAY 0.872340 (-3475 2125);
DISPLAY INVISIBLE (-3475 2125);
FORCEPROP 1 LAST PATH I24
J 2
(-3148 2250);
DISPLAY 0.872340 (-3148 2250);
PAINT GREEN (-3148 2250);
DISPLAY INVISIBLE (-3148 2250);
FORCEADD TAP..1
R 2
(-3150 2300);
FORCEPROP 3 LASTPIN (-3100 2300) SIG_NAME M_G_CPU1_SB_CB<2>
J 0
(-3090 2310);
DISPLAY 0.659574 (-3090 2310);
PAINT MONO (-3090 2310);
DISPLAY INVISIBLE (-3090 2310);
FORCEPROP 1 LASTPIN (-3100 2300) BN 2
J 2
(-3088 2308);
DISPLAY 0.680851 (-3088 2308);
PAINT GREEN (-3088 2308);
FORCEPROP 2 LAST CDS_LIB standard
J 0
(-3150 2300);
DISPLAY INVISIBLE (-3150 2300);
FORCEPROP 1 LAST BODY_TYPE PLUMBING
J 2
(-3150 2350);
DISPLAY 0.872340 (-3150 2350);
PAINT GREEN (-3150 2350);
DISPLAY INVISIBLE (-3150 2350);
FORCEPROP 1 LAST HDL_TAP TRUE
J 2
(-3475 2175);
DISPLAY 0.872340 (-3475 2175);
DISPLAY INVISIBLE (-3475 2175);
FORCEPROP 1 LAST PATH I25
J 2
(-3148 2300);
DISPLAY 0.872340 (-3148 2300);
PAINT GREEN (-3148 2300);
DISPLAY INVISIBLE (-3148 2300);
FORCEADD TAP..1
R 2
(-3150 2350);
FORCEPROP 3 LASTPIN (-3100 2350) SIG_NAME M_G_CPU1_SB_CB<3>
J 0
(-3090 2360);
DISPLAY 0.659574 (-3090 2360);
PAINT MONO (-3090 2360);
DISPLAY INVISIBLE (-3090 2360);
FORCEPROP 1 LASTPIN (-3100 2350) BN 3
J 2
(-3088 2358);
DISPLAY 0.680851 (-3088 2358);
PAINT GREEN (-3088 2358);
FORCEPROP 2 LAST CDS_LIB standard
J 0
(-3150 2350);
DISPLAY INVISIBLE (-3150 2350);
FORCEPROP 1 LAST BODY_TYPE PLUMBING
J 2
(-3150 2400);
DISPLAY 0.872340 (-3150 2400);
PAINT GREEN (-3150 2400);
DISPLAY INVISIBLE (-3150 2400);
FORCEPROP 1 LAST HDL_TAP TRUE
J 2
(-3475 2225);
DISPLAY 0.872340 (-3475 2225);
DISPLAY INVISIBLE (-3475 2225);
FORCEPROP 1 LAST PATH I26
J 2
(-3148 2350);
DISPLAY 0.872340 (-3148 2350);
PAINT GREEN (-3148 2350);
DISPLAY INVISIBLE (-3148 2350);
FORCEADD TAP..1
R 2
(-3150 2400);
FORCEPROP 3 LASTPIN (-3100 2400) SIG_NAME M_G_CPU1_SB_CB<4>
J 0
(-3090 2410);
DISPLAY 0.659574 (-3090 2410);
PAINT MONO (-3090 2410);
DISPLAY INVISIBLE (-3090 2410);
FORCEPROP 1 LASTPIN (-3100 2400) BN 4
J 2
(-3088 2408);
DISPLAY 0.680851 (-3088 2408);
PAINT GREEN (-3088 2408);
FORCEPROP 2 LAST CDS_LIB standard
J 0
(-3150 2400);
DISPLAY INVISIBLE (-3150 2400);
FORCEPROP 1 LAST BODY_TYPE PLUMBING
J 2
(-3150 2450);
DISPLAY 0.872340 (-3150 2450);
PAINT GREEN (-3150 2450);
DISPLAY INVISIBLE (-3150 2450);
FORCEPROP 1 LAST HDL_TAP TRUE
J 2
(-3475 2275);
DISPLAY 0.872340 (-3475 2275);
DISPLAY INVISIBLE (-3475 2275);
FORCEPROP 1 LAST PATH I27
J 2
(-3148 2400);
DISPLAY 0.872340 (-3148 2400);
PAINT GREEN (-3148 2400);
DISPLAY INVISIBLE (-3148 2400);
FORCEADD TAP..1
R 2
(-3150 2450);
FORCEPROP 3 LASTPIN (-3100 2450) SIG_NAME M_G_CPU1_SB_CB<5>
J 0
(-3090 2460);
DISPLAY 0.659574 (-3090 2460);
PAINT MONO (-3090 2460);
DISPLAY INVISIBLE (-3090 2460);
FORCEPROP 1 LASTPIN (-3100 2450) BN 5
J 2
(-3088 2458);
DISPLAY 0.680851 (-3088 2458);
PAINT GREEN (-3088 2458);
FORCEPROP 2 LAST CDS_LIB standard
J 0
(-3150 2450);
DISPLAY INVISIBLE (-3150 2450);
FORCEPROP 1 LAST BODY_TYPE PLUMBING
J 2
(-3150 2500);
DISPLAY 0.872340 (-3150 2500);
PAINT GREEN (-3150 2500);
DISPLAY INVISIBLE (-3150 2500);
FORCEPROP 1 LAST HDL_TAP TRUE
J 2
(-3475 2325);
DISPLAY 0.872340 (-3475 2325);
DISPLAY INVISIBLE (-3475 2325);
FORCEPROP 1 LAST PATH I28
J 2
(-3148 2450);
DISPLAY 0.872340 (-3148 2450);
PAINT GREEN (-3148 2450);
DISPLAY INVISIBLE (-3148 2450);
FORCEADD TAP..1
R 2
(-3150 2500);
FORCEPROP 3 LASTPIN (-3100 2500) SIG_NAME M_G_CPU1_SB_CB<6>
J 0
(-3090 2510);
DISPLAY 0.659574 (-3090 2510);
PAINT MONO (-3090 2510);
DISPLAY INVISIBLE (-3090 2510);
FORCEPROP 1 LASTPIN (-3100 2500) BN 6
J 2
(-3088 2508);
DISPLAY 0.680851 (-3088 2508);
PAINT GREEN (-3088 2508);
FORCEPROP 2 LAST CDS_LIB standard
J 0
(-3150 2500);
DISPLAY INVISIBLE (-3150 2500);
FORCEPROP 1 LAST BODY_TYPE PLUMBING
J 2
(-3150 2550);
DISPLAY 0.872340 (-3150 2550);
PAINT GREEN (-3150 2550);
DISPLAY INVISIBLE (-3150 2550);
FORCEPROP 1 LAST HDL_TAP TRUE
J 2
(-3475 2375);
DISPLAY 0.872340 (-3475 2375);
DISPLAY INVISIBLE (-3475 2375);
FORCEPROP 1 LAST PATH I29
J 2
(-3148 2500);
DISPLAY 0.872340 (-3148 2500);
PAINT GREEN (-3148 2500);
DISPLAY INVISIBLE (-3148 2500);
FORCEADD OFFPAGE..2
R 2
(-4075 1000);
FORCEPROP 2 LAST $XR0 57 
J 0
(-4299 1000);
DISPLAY 0.638298 (-4299 1000);
PAINT MONO (-4299 1000);
FORCEPROP 2 LAST CDS_LIB standard
J 0
(-4075 1000);
PAINT MONO (-4075 1000);
DISPLAY INVISIBLE (-4075 1000);
FORCEPROP 1 LAST OFFPAGE TRUE
J 2
(-4400 875);
DISPLAY 0.872340 (-4400 875);
DISPLAY INVISIBLE (-4400 875);
FORCEPROP 1 LAST COMMENT_BODY TRUE
J 2
(-4030 905);
DISPLAY 0.872340 (-4030 905);
PAINT GREEN (-4030 905);
DISPLAY INVISIBLE (-4030 905);
FORCEPROP 2 LAST PATH I3
J 0
(-4025 1075);
DISPLAY 1.021277 (-4025 1075);
DISPLAY INVISIBLE (-4025 1075);
FORCEADD TAP..1
R 2
(-3150 2550);
FORCEPROP 3 LASTPIN (-3100 2550) SIG_NAME M_G_CPU1_SB_CB<7>
J 0
(-3090 2560);
DISPLAY 0.659574 (-3090 2560);
PAINT MONO (-3090 2560);
DISPLAY INVISIBLE (-3090 2560);
FORCEPROP 1 LASTPIN (-3100 2550) BN 7
J 2
(-3088 2558);
DISPLAY 0.680851 (-3088 2558);
PAINT GREEN (-3088 2558);
FORCEPROP 2 LAST CDS_LIB standard
J 0
(-3150 2550);
DISPLAY INVISIBLE (-3150 2550);
FORCEPROP 1 LAST BODY_TYPE PLUMBING
J 2
(-3150 2600);
DISPLAY 0.872340 (-3150 2600);
PAINT GREEN (-3150 2600);
DISPLAY INVISIBLE (-3150 2600);
FORCEPROP 1 LAST HDL_TAP TRUE
J 2
(-3475 2425);
DISPLAY 0.872340 (-3475 2425);
DISPLAY INVISIBLE (-3475 2425);
FORCEPROP 1 LAST PATH I30
J 2
(-3148 2550);
DISPLAY 0.872340 (-3148 2550);
PAINT GREEN (-3148 2550);
DISPLAY INVISIBLE (-3148 2550);
FORCEADD TAP..1
R 2
(-3150 2700);
FORCEPROP 3 LASTPIN (-3100 2700) SIG_NAME M_G_CPU1_SA_CB<1>
J 0
(-3090 2710);
DISPLAY 0.659574 (-3090 2710);
PAINT MONO (-3090 2710);
DISPLAY INVISIBLE (-3090 2710);
FORCEPROP 1 LASTPIN (-3100 2700) BN 1
J 2
(-3088 2708);
DISPLAY 0.680851 (-3088 2708);
PAINT GREEN (-3088 2708);
FORCEPROP 2 LAST CDS_LIB standard
J 0
(-3150 2700);
DISPLAY INVISIBLE (-3150 2700);
FORCEPROP 1 LAST BODY_TYPE PLUMBING
J 2
(-3150 2750);
DISPLAY 0.872340 (-3150 2750);
PAINT GREEN (-3150 2750);
DISPLAY INVISIBLE (-3150 2750);
FORCEPROP 1 LAST HDL_TAP TRUE
J 2
(-3475 2575);
DISPLAY 0.872340 (-3475 2575);
DISPLAY INVISIBLE (-3475 2575);
FORCEPROP 1 LAST PATH I31
J 2
(-3148 2700);
DISPLAY 0.872340 (-3148 2700);
PAINT GREEN (-3148 2700);
DISPLAY INVISIBLE (-3148 2700);
FORCEADD TAP..1
R 2
(-3150 2650);
FORCEPROP 3 LASTPIN (-3100 2650) SIG_NAME M_G_CPU1_SA_CB<0>
J 0
(-3090 2660);
DISPLAY 0.659574 (-3090 2660);
PAINT MONO (-3090 2660);
DISPLAY INVISIBLE (-3090 2660);
FORCEPROP 1 LASTPIN (-3100 2650) BN 0
J 2
(-3088 2658);
DISPLAY 0.680851 (-3088 2658);
PAINT GREEN (-3088 2658);
FORCEPROP 2 LAST CDS_LIB standard
J 0
(-3150 2650);
PAINT MONO (-3150 2650);
DISPLAY INVISIBLE (-3150 2650);
FORCEPROP 1 LAST BODY_TYPE PLUMBING
J 2
(-3150 2700);
DISPLAY 0.872340 (-3150 2700);
PAINT GREEN (-3150 2700);
DISPLAY INVISIBLE (-3150 2700);
FORCEPROP 1 LAST HDL_TAP TRUE
J 2
(-3475 2525);
DISPLAY 0.872340 (-3475 2525);
DISPLAY INVISIBLE (-3475 2525);
FORCEPROP 1 LAST PATH I32
J 2
(-3148 2650);
DISPLAY 0.872340 (-3148 2650);
PAINT GREEN (-3148 2650);
DISPLAY INVISIBLE (-3148 2650);
FORCEADD TAP..1
R 2
(-3150 2750);
FORCEPROP 3 LASTPIN (-3100 2750) SIG_NAME M_G_CPU1_SA_CB<2>
J 0
(-3090 2760);
DISPLAY 0.659574 (-3090 2760);
PAINT MONO (-3090 2760);
DISPLAY INVISIBLE (-3090 2760);
FORCEPROP 1 LASTPIN (-3100 2750) BN 2
J 2
(-3088 2758);
DISPLAY 0.680851 (-3088 2758);
PAINT GREEN (-3088 2758);
FORCEPROP 2 LAST CDS_LIB standard
J 0
(-3150 2750);
DISPLAY INVISIBLE (-3150 2750);
FORCEPROP 1 LAST BODY_TYPE PLUMBING
J 2
(-3150 2800);
DISPLAY 0.872340 (-3150 2800);
PAINT GREEN (-3150 2800);
DISPLAY INVISIBLE (-3150 2800);
FORCEPROP 1 LAST HDL_TAP TRUE
J 2
(-3475 2625);
DISPLAY 0.872340 (-3475 2625);
DISPLAY INVISIBLE (-3475 2625);
FORCEPROP 1 LAST PATH I33
J 2
(-3148 2750);
DISPLAY 0.872340 (-3148 2750);
PAINT GREEN (-3148 2750);
DISPLAY INVISIBLE (-3148 2750);
FORCEADD TAP..1
R 2
(-3150 2800);
FORCEPROP 3 LASTPIN (-3100 2800) SIG_NAME M_G_CPU1_SA_CB<3>
J 0
(-3090 2810);
DISPLAY 0.659574 (-3090 2810);
PAINT MONO (-3090 2810);
DISPLAY INVISIBLE (-3090 2810);
FORCEPROP 1 LASTPIN (-3100 2800) BN 3
J 2
(-3088 2808);
DISPLAY 0.680851 (-3088 2808);
PAINT GREEN (-3088 2808);
FORCEPROP 2 LAST CDS_LIB standard
J 0
(-3150 2800);
DISPLAY INVISIBLE (-3150 2800);
FORCEPROP 1 LAST BODY_TYPE PLUMBING
J 2
(-3150 2850);
DISPLAY 0.872340 (-3150 2850);
PAINT GREEN (-3150 2850);
DISPLAY INVISIBLE (-3150 2850);
FORCEPROP 1 LAST HDL_TAP TRUE
J 2
(-3475 2675);
DISPLAY 0.872340 (-3475 2675);
DISPLAY INVISIBLE (-3475 2675);
FORCEPROP 1 LAST PATH I34
J 2
(-3148 2800);
DISPLAY 0.872340 (-3148 2800);
PAINT GREEN (-3148 2800);
DISPLAY INVISIBLE (-3148 2800);
FORCEADD TAP..1
R 2
(-3150 2850);
FORCEPROP 3 LASTPIN (-3100 2850) SIG_NAME M_G_CPU1_SA_CB<4>
J 0
(-3090 2860);
DISPLAY 0.659574 (-3090 2860);
PAINT MONO (-3090 2860);
DISPLAY INVISIBLE (-3090 2860);
FORCEPROP 1 LASTPIN (-3100 2850) BN 4
J 2
(-3088 2858);
DISPLAY 0.680851 (-3088 2858);
PAINT GREEN (-3088 2858);
FORCEPROP 2 LAST CDS_LIB standard
J 0
(-3150 2850);
DISPLAY INVISIBLE (-3150 2850);
FORCEPROP 1 LAST BODY_TYPE PLUMBING
J 2
(-3150 2900);
DISPLAY 0.872340 (-3150 2900);
PAINT GREEN (-3150 2900);
DISPLAY INVISIBLE (-3150 2900);
FORCEPROP 1 LAST HDL_TAP TRUE
J 2
(-3475 2725);
DISPLAY 0.872340 (-3475 2725);
DISPLAY INVISIBLE (-3475 2725);
FORCEPROP 1 LAST PATH I35
J 2
(-3148 2850);
DISPLAY 0.872340 (-3148 2850);
PAINT GREEN (-3148 2850);
DISPLAY INVISIBLE (-3148 2850);
FORCEADD TAP..1
R 2
(-3150 2900);
FORCEPROP 3 LASTPIN (-3100 2900) SIG_NAME M_G_CPU1_SA_CB<5>
J 0
(-3090 2910);
DISPLAY 0.659574 (-3090 2910);
PAINT MONO (-3090 2910);
DISPLAY INVISIBLE (-3090 2910);
FORCEPROP 1 LASTPIN (-3100 2900) BN 5
J 2
(-3088 2908);
DISPLAY 0.680851 (-3088 2908);
PAINT GREEN (-3088 2908);
FORCEPROP 2 LAST CDS_LIB standard
J 0
(-3150 2900);
DISPLAY INVISIBLE (-3150 2900);
FORCEPROP 1 LAST BODY_TYPE PLUMBING
J 2
(-3150 2950);
DISPLAY 0.872340 (-3150 2950);
PAINT GREEN (-3150 2950);
DISPLAY INVISIBLE (-3150 2950);
FORCEPROP 1 LAST HDL_TAP TRUE
J 2
(-3475 2775);
DISPLAY 0.872340 (-3475 2775);
DISPLAY INVISIBLE (-3475 2775);
FORCEPROP 1 LAST PATH I36
J 2
(-3148 2900);
DISPLAY 0.872340 (-3148 2900);
PAINT GREEN (-3148 2900);
DISPLAY INVISIBLE (-3148 2900);
FORCEADD TAP..1
R 2
(-3150 2950);
FORCEPROP 3 LASTPIN (-3100 2950) SIG_NAME M_G_CPU1_SA_CB<6>
J 0
(-3090 2960);
DISPLAY 0.659574 (-3090 2960);
PAINT MONO (-3090 2960);
DISPLAY INVISIBLE (-3090 2960);
FORCEPROP 1 LASTPIN (-3100 2950) BN 6
J 2
(-3088 2958);
DISPLAY 0.680851 (-3088 2958);
PAINT GREEN (-3088 2958);
FORCEPROP 2 LAST CDS_LIB standard
J 0
(-3150 2950);
DISPLAY INVISIBLE (-3150 2950);
FORCEPROP 1 LAST BODY_TYPE PLUMBING
J 2
(-3150 3000);
DISPLAY 0.872340 (-3150 3000);
PAINT GREEN (-3150 3000);
DISPLAY INVISIBLE (-3150 3000);
FORCEPROP 1 LAST HDL_TAP TRUE
J 2
(-3475 2825);
DISPLAY 0.872340 (-3475 2825);
DISPLAY INVISIBLE (-3475 2825);
FORCEPROP 1 LAST PATH I37
J 2
(-3148 2950);
DISPLAY 0.872340 (-3148 2950);
PAINT GREEN (-3148 2950);
DISPLAY INVISIBLE (-3148 2950);
FORCEADD TAP..1
R 2
(-3150 3000);
FORCEPROP 3 LASTPIN (-3100 3000) SIG_NAME M_G_CPU1_SA_CB<7>
J 0
(-3090 3010);
DISPLAY 0.659574 (-3090 3010);
PAINT MONO (-3090 3010);
DISPLAY INVISIBLE (-3090 3010);
FORCEPROP 1 LASTPIN (-3100 3000) BN 7
J 2
(-3088 3008);
DISPLAY 0.680851 (-3088 3008);
PAINT GREEN (-3088 3008);
FORCEPROP 2 LAST CDS_LIB standard
J 0
(-3150 3000);
DISPLAY INVISIBLE (-3150 3000);
FORCEPROP 1 LAST BODY_TYPE PLUMBING
J 2
(-3150 3050);
DISPLAY 0.872340 (-3150 3050);
PAINT GREEN (-3150 3050);
DISPLAY INVISIBLE (-3150 3050);
FORCEPROP 1 LAST HDL_TAP TRUE
J 2
(-3475 2875);
DISPLAY 0.872340 (-3475 2875);
DISPLAY INVISIBLE (-3475 2875);
FORCEPROP 1 LAST PATH I38
J 2
(-3148 3000);
DISPLAY 0.872340 (-3148 3000);
PAINT GREEN (-3148 3000);
DISPLAY INVISIBLE (-3148 3000);
FORCEADD TAP..1
R 2
(-3150 3750);
FORCEPROP 3 LASTPIN (-3100 3750) SIG_NAME M_G_CPU1_SB_CA<1>
J 0
(-3090 3760);
DISPLAY 0.659574 (-3090 3760);
PAINT MONO (-3090 3760);
DISPLAY INVISIBLE (-3090 3760);
FORCEPROP 1 LASTPIN (-3100 3750) BN 1
J 2
(-3088 3758);
DISPLAY 0.680851 (-3088 3758);
PAINT GREEN (-3088 3758);
FORCEPROP 2 LAST CDS_LIB standard
J 0
(-3150 3750);
DISPLAY INVISIBLE (-3150 3750);
FORCEPROP 1 LAST BODY_TYPE PLUMBING
J 2
(-3150 3800);
DISPLAY 0.872340 (-3150 3800);
PAINT GREEN (-3150 3800);
DISPLAY INVISIBLE (-3150 3800);
FORCEPROP 1 LAST HDL_TAP TRUE
J 2
(-3475 3625);
DISPLAY 0.872340 (-3475 3625);
DISPLAY INVISIBLE (-3475 3625);
FORCEPROP 1 LAST PATH I39
J 2
(-3148 3750);
DISPLAY 0.872340 (-3148 3750);
PAINT GREEN (-3148 3750);
DISPLAY INVISIBLE (-3148 3750);
FORCEADD UNIVERSAL_GND..1
(-2925 25);
FORCEPROP 3 LASTPIN (-2925 75) SIG_NAME GND\g
J 0
(-2915 85);
DISPLAY 0.659574 (-2915 85);
PAINT MONO (-2915 85);
DISPLAY INVISIBLE (-2915 85);
FORCEPROP 1 LAST PATH I4
J 0
(-2850 25);
DISPLAY 0.872340 (-2850 25);
PAINT AQUA (-2850 25);
DISPLAY INVISIBLE (-2850 25);
FORCEPROP 1 LAST HDL_POWER GND
J 1
(-2900 -50);
DISPLAY 0.872340 (-2900 -50);
PAINT GREEN (-2900 -50);
DISPLAY INVISIBLE (-2900 -50);
FORCEPROP 2 LAST CDS_LIB logical_power
J 0
(-2925 25);
PAINT MONO (-2925 25);
DISPLAY INVISIBLE (-2925 25);
FORCEADD TAP..1
R 2
(-3150 3700);
FORCEPROP 3 LASTPIN (-3100 3700) SIG_NAME M_G_CPU1_SB_CA<0>
J 0
(-3090 3710);
DISPLAY 0.659574 (-3090 3710);
PAINT MONO (-3090 3710);
DISPLAY INVISIBLE (-3090 3710);
FORCEPROP 1 LASTPIN (-3100 3700) BN 0
J 2
(-3088 3708);
DISPLAY 0.680851 (-3088 3708);
PAINT GREEN (-3088 3708);
FORCEPROP 2 LAST CDS_LIB standard
J 0
(-3150 3700);
DISPLAY INVISIBLE (-3150 3700);
FORCEPROP 1 LAST BODY_TYPE PLUMBING
J 2
(-3150 3750);
DISPLAY 0.872340 (-3150 3750);
PAINT GREEN (-3150 3750);
DISPLAY INVISIBLE (-3150 3750);
FORCEPROP 1 LAST HDL_TAP TRUE
J 2
(-3475 3575);
DISPLAY 0.872340 (-3475 3575);
DISPLAY INVISIBLE (-3475 3575);
FORCEPROP 1 LAST PATH I40
J 2
(-3148 3700);
DISPLAY 0.872340 (-3148 3700);
PAINT GREEN (-3148 3700);
DISPLAY INVISIBLE (-3148 3700);
FORCEADD TAP..1
R 2
(-3150 3800);
FORCEPROP 3 LASTPIN (-3100 3800) SIG_NAME M_G_CPU1_SB_CA<2>
J 0
(-3090 3810);
DISPLAY 0.659574 (-3090 3810);
PAINT MONO (-3090 3810);
DISPLAY INVISIBLE (-3090 3810);
FORCEPROP 1 LASTPIN (-3100 3800) BN 2
J 2
(-3088 3808);
DISPLAY 0.680851 (-3088 3808);
PAINT GREEN (-3088 3808);
FORCEPROP 2 LAST CDS_LIB standard
J 0
(-3150 3800);
DISPLAY INVISIBLE (-3150 3800);
FORCEPROP 1 LAST BODY_TYPE PLUMBING
J 2
(-3150 3850);
DISPLAY 0.872340 (-3150 3850);
PAINT GREEN (-3150 3850);
DISPLAY INVISIBLE (-3150 3850);
FORCEPROP 1 LAST HDL_TAP TRUE
J 2
(-3475 3675);
DISPLAY 0.872340 (-3475 3675);
DISPLAY INVISIBLE (-3475 3675);
FORCEPROP 1 LAST PATH I41
J 2
(-3148 3800);
DISPLAY 0.872340 (-3148 3800);
PAINT GREEN (-3148 3800);
DISPLAY INVISIBLE (-3148 3800);
FORCEADD TAP..1
R 2
(-3150 3850);
FORCEPROP 3 LASTPIN (-3100 3850) SIG_NAME M_G_CPU1_SB_CA<3>
J 0
(-3090 3860);
DISPLAY 0.659574 (-3090 3860);
PAINT MONO (-3090 3860);
DISPLAY INVISIBLE (-3090 3860);
FORCEPROP 1 LASTPIN (-3100 3850) BN 3
J 2
(-3088 3858);
DISPLAY 0.680851 (-3088 3858);
PAINT GREEN (-3088 3858);
FORCEPROP 2 LAST CDS_LIB standard
J 0
(-3150 3850);
DISPLAY INVISIBLE (-3150 3850);
FORCEPROP 1 LAST BODY_TYPE PLUMBING
J 2
(-3150 3900);
DISPLAY 0.872340 (-3150 3900);
PAINT GREEN (-3150 3900);
DISPLAY INVISIBLE (-3150 3900);
FORCEPROP 1 LAST HDL_TAP TRUE
J 2
(-3475 3725);
DISPLAY 0.872340 (-3475 3725);
DISPLAY INVISIBLE (-3475 3725);
FORCEPROP 1 LAST PATH I42
J 2
(-3148 3850);
DISPLAY 0.872340 (-3148 3850);
PAINT GREEN (-3148 3850);
DISPLAY INVISIBLE (-3148 3850);
FORCEADD TAP..1
R 2
(-3150 3900);
FORCEPROP 3 LASTPIN (-3100 3900) SIG_NAME M_G_CPU1_SB_CA<4>
J 0
(-3090 3910);
DISPLAY 0.659574 (-3090 3910);
PAINT MONO (-3090 3910);
DISPLAY INVISIBLE (-3090 3910);
FORCEPROP 1 LASTPIN (-3100 3900) BN 4
J 2
(-3088 3908);
DISPLAY 0.680851 (-3088 3908);
PAINT GREEN (-3088 3908);
FORCEPROP 2 LAST CDS_LIB standard
J 0
(-3150 3900);
DISPLAY INVISIBLE (-3150 3900);
FORCEPROP 1 LAST BODY_TYPE PLUMBING
J 2
(-3150 3950);
DISPLAY 0.872340 (-3150 3950);
PAINT GREEN (-3150 3950);
DISPLAY INVISIBLE (-3150 3950);
FORCEPROP 1 LAST HDL_TAP TRUE
J 2
(-3475 3775);
DISPLAY 0.872340 (-3475 3775);
DISPLAY INVISIBLE (-3475 3775);
FORCEPROP 1 LAST PATH I43
J 2
(-3148 3900);
DISPLAY 0.872340 (-3148 3900);
PAINT GREEN (-3148 3900);
DISPLAY INVISIBLE (-3148 3900);
FORCEADD TAP..1
R 2
(-3150 3950);
FORCEPROP 3 LASTPIN (-3100 3950) SIG_NAME M_G_CPU1_SB_CA<5>
J 0
(-3090 3960);
DISPLAY 0.659574 (-3090 3960);
PAINT MONO (-3090 3960);
DISPLAY INVISIBLE (-3090 3960);
FORCEPROP 1 LASTPIN (-3100 3950) BN 5
J 2
(-3088 3958);
DISPLAY 0.680851 (-3088 3958);
PAINT GREEN (-3088 3958);
FORCEPROP 2 LAST CDS_LIB standard
J 0
(-3150 3950);
DISPLAY INVISIBLE (-3150 3950);
FORCEPROP 1 LAST BODY_TYPE PLUMBING
J 2
(-3150 4000);
DISPLAY 0.872340 (-3150 4000);
PAINT GREEN (-3150 4000);
DISPLAY INVISIBLE (-3150 4000);
FORCEPROP 1 LAST HDL_TAP TRUE
J 2
(-3475 3825);
DISPLAY 0.872340 (-3475 3825);
DISPLAY INVISIBLE (-3475 3825);
FORCEPROP 1 LAST PATH I44
J 2
(-3148 3950);
DISPLAY 0.872340 (-3148 3950);
PAINT GREEN (-3148 3950);
DISPLAY INVISIBLE (-3148 3950);
FORCEADD TAP..1
R 2
(-3150 4000);
FORCEPROP 3 LASTPIN (-3100 4000) SIG_NAME M_G_CPU1_SB_CA<6>
J 0
(-3090 4010);
DISPLAY 0.659574 (-3090 4010);
PAINT MONO (-3090 4010);
DISPLAY INVISIBLE (-3090 4010);
FORCEPROP 1 LASTPIN (-3100 4000) BN 6
J 2
(-3088 4008);
DISPLAY 0.680851 (-3088 4008);
PAINT GREEN (-3088 4008);
FORCEPROP 2 LAST CDS_LIB standard
J 0
(-3150 4000);
DISPLAY INVISIBLE (-3150 4000);
FORCEPROP 1 LAST BODY_TYPE PLUMBING
J 2
(-3150 4050);
DISPLAY 0.872340 (-3150 4050);
PAINT GREEN (-3150 4050);
DISPLAY INVISIBLE (-3150 4050);
FORCEPROP 1 LAST HDL_TAP TRUE
J 2
(-3475 3875);
DISPLAY 0.872340 (-3475 3875);
DISPLAY INVISIBLE (-3475 3875);
FORCEPROP 1 LAST PATH I45
J 2
(-3148 4000);
DISPLAY 0.872340 (-3148 4000);
PAINT GREEN (-3148 4000);
DISPLAY INVISIBLE (-3148 4000);
FORCEADD TAP..1
R 2
(-3150 4100);
FORCEPROP 3 LASTPIN (-3100 4100) SIG_NAME M_G_CPU1_SA_CA<0>
J 0
(-3090 4110);
DISPLAY 0.659574 (-3090 4110);
PAINT MONO (-3090 4110);
DISPLAY INVISIBLE (-3090 4110);
FORCEPROP 1 LASTPIN (-3100 4100) BN 0
J 2
(-3088 4108);
DISPLAY 0.680851 (-3088 4108);
PAINT GREEN (-3088 4108);
FORCEPROP 2 LAST CDS_LIB standard
J 0
(-3150 4100);
DISPLAY INVISIBLE (-3150 4100);
FORCEPROP 1 LAST BODY_TYPE PLUMBING
J 2
(-3150 4150);
DISPLAY 0.872340 (-3150 4150);
PAINT GREEN (-3150 4150);
DISPLAY INVISIBLE (-3150 4150);
FORCEPROP 1 LAST HDL_TAP TRUE
J 2
(-3475 3975);
DISPLAY 0.872340 (-3475 3975);
DISPLAY INVISIBLE (-3475 3975);
FORCEPROP 1 LAST PATH I46
J 2
(-3148 4100);
DISPLAY 0.872340 (-3148 4100);
PAINT GREEN (-3148 4100);
DISPLAY INVISIBLE (-3148 4100);
FORCEADD TAP..1
R 2
(-3150 4150);
FORCEPROP 3 LASTPIN (-3100 4150) SIG_NAME M_G_CPU1_SA_CA<1>
J 0
(-3090 4160);
DISPLAY 0.659574 (-3090 4160);
PAINT MONO (-3090 4160);
DISPLAY INVISIBLE (-3090 4160);
FORCEPROP 1 LASTPIN (-3100 4150) BN 1
J 2
(-3088 4158);
DISPLAY 0.680851 (-3088 4158);
PAINT GREEN (-3088 4158);
FORCEPROP 2 LAST CDS_LIB standard
J 0
(-3150 4150);
DISPLAY INVISIBLE (-3150 4150);
FORCEPROP 1 LAST BODY_TYPE PLUMBING
J 2
(-3150 4200);
DISPLAY 0.872340 (-3150 4200);
PAINT GREEN (-3150 4200);
DISPLAY INVISIBLE (-3150 4200);
FORCEPROP 1 LAST HDL_TAP TRUE
J 2
(-3475 4025);
DISPLAY 0.872340 (-3475 4025);
DISPLAY INVISIBLE (-3475 4025);
FORCEPROP 1 LAST PATH I47
J 2
(-3148 4150);
DISPLAY 0.872340 (-3148 4150);
PAINT GREEN (-3148 4150);
DISPLAY INVISIBLE (-3148 4150);
FORCEADD TAP..1
R 2
(-3150 4200);
FORCEPROP 3 LASTPIN (-3100 4200) SIG_NAME M_G_CPU1_SA_CA<2>
J 0
(-3090 4210);
DISPLAY 0.659574 (-3090 4210);
PAINT MONO (-3090 4210);
DISPLAY INVISIBLE (-3090 4210);
FORCEPROP 1 LASTPIN (-3100 4200) BN 2
J 2
(-3088 4208);
DISPLAY 0.680851 (-3088 4208);
PAINT GREEN (-3088 4208);
FORCEPROP 2 LAST CDS_LIB standard
J 0
(-3150 4200);
DISPLAY INVISIBLE (-3150 4200);
FORCEPROP 1 LAST BODY_TYPE PLUMBING
J 2
(-3150 4250);
DISPLAY 0.872340 (-3150 4250);
PAINT GREEN (-3150 4250);
DISPLAY INVISIBLE (-3150 4250);
FORCEPROP 1 LAST HDL_TAP TRUE
J 2
(-3475 4075);
DISPLAY 0.872340 (-3475 4075);
DISPLAY INVISIBLE (-3475 4075);
FORCEPROP 1 LAST PATH I48
J 2
(-3148 4200);
DISPLAY 0.872340 (-3148 4200);
PAINT GREEN (-3148 4200);
DISPLAY INVISIBLE (-3148 4200);
FORCEADD TAP..1
R 2
(-3150 4250);
FORCEPROP 3 LASTPIN (-3100 4250) SIG_NAME M_G_CPU1_SA_CA<3>
J 0
(-3090 4260);
DISPLAY 0.659574 (-3090 4260);
PAINT MONO (-3090 4260);
DISPLAY INVISIBLE (-3090 4260);
FORCEPROP 1 LASTPIN (-3100 4250) BN 3
J 2
(-3088 4258);
DISPLAY 0.680851 (-3088 4258);
PAINT GREEN (-3088 4258);
FORCEPROP 2 LAST CDS_LIB standard
J 0
(-3150 4250);
DISPLAY INVISIBLE (-3150 4250);
FORCEPROP 1 LAST BODY_TYPE PLUMBING
J 2
(-3150 4300);
DISPLAY 0.872340 (-3150 4300);
PAINT GREEN (-3150 4300);
DISPLAY INVISIBLE (-3150 4300);
FORCEPROP 1 LAST HDL_TAP TRUE
J 2
(-3475 4125);
DISPLAY 0.872340 (-3475 4125);
DISPLAY INVISIBLE (-3475 4125);
FORCEPROP 1 LAST PATH I49
J 2
(-3148 4250);
DISPLAY 0.872340 (-3148 4250);
PAINT GREEN (-3148 4250);
DISPLAY INVISIBLE (-3148 4250);
FORCEADD Q_RES..2
(-2925 250);
FORCEPROP 1 LAST PART_NUMBER CS38452FB05
J 0
(-2885 125);
DISPLAY 0.978723 (-2885 125);
DISPLAY INVISIBLE (-2885 125);
FORCEPROP 1 LAST WATTAGE 1/16W
J 0
(-2885 225);
DISPLAY 0.978723 (-2885 225);
FORCEPROP 1 LAST MATERIAL CHIP
J 0
(-2885 175);
DISPLAY 0.978723 (-2885 175);
FORCEPROP 1 LAST TOLERANCE 1%
J 0
(-2880 275);
DISPLAY 0.978723 (-2880 275);
FORCEPROP 1 LAST PACK_TYPE 0402LF
J 0
(-2885 75);
DISPLAY 0.978723 (-2885 75);
FORCEPROP 1 LAST VALUE 84.5K
J 0
(-2880 325);
DISPLAY 0.978723 (-2880 325);
FORCEPROP 1 LAST $LOCATION R74
J 0
(-2880 375);
DISPLAY 0.978723 (-2880 375);
FORCEPROP 1 LASTPIN (-2925 350) $PN 1
J 0
(-2920 312);
DISPLAY 0.787234 (-2920 312);
FORCEPROP 1 LASTPIN (-2925 150) $PN 2
J 0
(-2920 160);
DISPLAY 0.787234 (-2920 160);
FORCEPROP 2 LAST CDS_LIB pure_quanta
J 0
(-2925 250);
PAINT MONO (-2925 250);
DISPLAY INVISIBLE (-2925 250);
FORCEPROP 1 LAST PATH I5
J 0
(-2875 425);
DISPLAY 0.978723 (-2875 425);
PAINT WHITE (-2875 425);
DISPLAY INVISIBLE (-2875 425);
FORCEPROP 1 LAST $LOCATION R74
J 0
(-2875 475);
DISPLAY 1.021277 (-2875 475);
DISPLAY INVISIBLE (-2875 475);
FORCEPROP 2 LAST CDS_LOCATION R74
J 0
(-2875 475);
DISPLAY 1.021277 (-2875 475);
DISPLAY INVISIBLE (-2875 475);
FORCEPROP 2 LAST $SEC 1
J 0
(-2875 475);
DISPLAY 0.680851 (-2875 475);
PAINT MONO (-2875 475);
DISPLAY INVISIBLE (-2875 475);
FORCEPROP 2 LAST CDS_SEC 1
J 0
(-2875 475);
DISPLAY 1.021277 (-2875 475);
DISPLAY INVISIBLE (-2875 475);
FORCEADD TAP..1
R 2
(-3150 4350);
FORCEPROP 3 LASTPIN (-3100 4350) SIG_NAME M_G_CPU1_SA_CA<5>
J 0
(-3090 4360);
DISPLAY 0.659574 (-3090 4360);
PAINT MONO (-3090 4360);
DISPLAY INVISIBLE (-3090 4360);
FORCEPROP 1 LASTPIN (-3100 4350) BN 5
J 2
(-3088 4358);
DISPLAY 0.680851 (-3088 4358);
PAINT GREEN (-3088 4358);
FORCEPROP 2 LAST CDS_LIB standard
J 0
(-3150 4350);
DISPLAY INVISIBLE (-3150 4350);
FORCEPROP 1 LAST BODY_TYPE PLUMBING
J 2
(-3150 4400);
DISPLAY 0.872340 (-3150 4400);
PAINT GREEN (-3150 4400);
DISPLAY INVISIBLE (-3150 4400);
FORCEPROP 1 LAST HDL_TAP TRUE
J 2
(-3475 4225);
DISPLAY 0.872340 (-3475 4225);
DISPLAY INVISIBLE (-3475 4225);
FORCEPROP 1 LAST PATH I50
J 2
(-3148 4350);
DISPLAY 0.872340 (-3148 4350);
PAINT GREEN (-3148 4350);
DISPLAY INVISIBLE (-3148 4350);
FORCEADD TAP..1
R 2
(-3150 4300);
FORCEPROP 3 LASTPIN (-3100 4300) SIG_NAME M_G_CPU1_SA_CA<4>
J 0
(-3090 4310);
DISPLAY 0.659574 (-3090 4310);
PAINT MONO (-3090 4310);
DISPLAY INVISIBLE (-3090 4310);
FORCEPROP 1 LASTPIN (-3100 4300) BN 4
J 2
(-3088 4308);
DISPLAY 0.680851 (-3088 4308);
PAINT GREEN (-3088 4308);
FORCEPROP 2 LAST CDS_LIB standard
J 0
(-3150 4300);
DISPLAY INVISIBLE (-3150 4300);
FORCEPROP 1 LAST BODY_TYPE PLUMBING
J 2
(-3150 4350);
DISPLAY 0.872340 (-3150 4350);
PAINT GREEN (-3150 4350);
DISPLAY INVISIBLE (-3150 4350);
FORCEPROP 1 LAST HDL_TAP TRUE
J 2
(-3475 4175);
DISPLAY 0.872340 (-3475 4175);
DISPLAY INVISIBLE (-3475 4175);
FORCEPROP 1 LAST PATH I51
J 2
(-3148 4300);
DISPLAY 0.872340 (-3148 4300);
PAINT GREEN (-3148 4300);
DISPLAY INVISIBLE (-3148 4300);
FORCEADD TAP..1
R 2
(-3150 4400);
FORCEPROP 3 LASTPIN (-3100 4400) SIG_NAME M_G_CPU1_SA_CA<6>
J 0
(-3090 4410);
DISPLAY 0.659574 (-3090 4410);
PAINT MONO (-3090 4410);
DISPLAY INVISIBLE (-3090 4410);
FORCEPROP 1 LASTPIN (-3100 4400) BN 6
J 2
(-3088 4408);
DISPLAY 0.680851 (-3088 4408);
PAINT GREEN (-3088 4408);
FORCEPROP 2 LAST CDS_LIB standard
J 0
(-3150 4400);
DISPLAY INVISIBLE (-3150 4400);
FORCEPROP 1 LAST BODY_TYPE PLUMBING
J 2
(-3150 4450);
DISPLAY 0.872340 (-3150 4450);
PAINT GREEN (-3150 4450);
DISPLAY INVISIBLE (-3150 4450);
FORCEPROP 1 LAST HDL_TAP TRUE
J 2
(-3475 4275);
DISPLAY 0.872340 (-3475 4275);
DISPLAY INVISIBLE (-3475 4275);
FORCEPROP 1 LAST PATH I52
J 2
(-3148 4400);
DISPLAY 0.872340 (-3148 4400);
PAINT GREEN (-3148 4400);
DISPLAY INVISIBLE (-3148 4400);
FORCEADD UNIVERSAL_GND..1
(225 150);
FORCEPROP 3 LASTPIN (225 200) SIG_NAME GND\g
J 0
(235 210);
DISPLAY 0.659574 (235 210);
PAINT MONO (235 210);
DISPLAY INVISIBLE (235 210);
FORCEPROP 1 LAST PATH I53
J 0
(300 150);
DISPLAY 0.872340 (300 150);
PAINT AQUA (300 150);
DISPLAY INVISIBLE (300 150);
FORCEPROP 1 LAST HDL_POWER GND
J 1
(250 75);
DISPLAY 0.872340 (250 75);
PAINT GREEN (250 75);
DISPLAY INVISIBLE (250 75);
FORCEPROP 2 LAST CDS_LIB logical_power
J 0
(225 150);
PAINT MONO (225 150);
DISPLAY INVISIBLE (225 150);
FORCEADD Q_CAP..1
(225 525);
FORCEPROP 1 LAST PART_NUMBER CH5221MEB00
J 0
(275 375);
DISPLAY 0.978723 (275 375);
DISPLAY INVISIBLE (275 375);
FORCEPROP 1 LAST VOLTAGE 6.3V
J 0
(275 525);
DISPLAY 0.978723 (275 525);
FORCEPROP 1 LAST TOLERANCE 20%
J 0
(275 475);
DISPLAY 0.978723 (275 475);
FORCEPROP 1 LAST PACK_TYPE C0402
J 0
(275 325);
DISPLAY 0.978723 (275 325);
FORCEPROP 1 LAST MATERIAL X6S
J 0
(275 425);
DISPLAY 0.978723 (275 425);
FORCEPROP 1 LAST VALUE 2.2UF
J 0
(275 575);
DISPLAY 0.978723 (275 575);
FORCEPROP 1 LAST $LOCATION C78
J 0
(275 625);
DISPLAY 0.978723 (275 625);
FORCEPROP 1 LASTPIN (225 625) $PN 1
J 0
(235 605);
DISPLAY 0.787234 (235 605);
FORCEPROP 1 LASTPIN (225 425) $PN 2
J 0
(235 405);
DISPLAY 0.787234 (235 405);
FORCEPROP 2 LAST CDS_LIB pure_quanta
J 0
(225 525);
PAINT MONO (225 525);
DISPLAY INVISIBLE (225 525);
FORCEPROP 1 LAST PATH I54
J 0
(275 675);
DISPLAY 0.978723 (275 675);
PAINT WHITE (275 675);
DISPLAY INVISIBLE (275 675);
FORCEPROP 1 LAST $LOCATION C78
J 0
(275 725);
DISPLAY 1.021277 (275 725);
DISPLAY INVISIBLE (275 725);
FORCEPROP 2 LAST CDS_LOCATION C78
J 0
(275 725);
DISPLAY 1.021277 (275 725);
DISPLAY INVISIBLE (275 725);
FORCEPROP 2 LAST $SEC 1
J 0
(275 725);
DISPLAY 0.680851 (275 725);
PAINT MONO (275 725);
DISPLAY INVISIBLE (275 725);
FORCEPROP 2 LAST CDS_SEC 1
J 0
(275 725);
DISPLAY 1.021277 (275 725);
DISPLAY INVISIBLE (275 725);
FORCEADD VCC_CORE..1
(225 850);
FORCEPROP 3 LASTPIN (225 800) SIG_NAME P3V3_AUX\g
J 0
(235 810);
DISPLAY 0.659574 (235 810);
PAINT MONO (235 810);
DISPLAY INVISIBLE (235 810);
FORCEPROP 1 LAST HDL_POWER P3V3_AUX
J 1
(225 900);
DISPLAY 1.148936 (225 900);
PAINT GREEN (225 900);
FORCEPROP 2 LAST CDS_LIB logical_power
J 0
(225 850);
PAINT MONO (225 850);
DISPLAY INVISIBLE (225 850);
FORCEPROP 1 LAST PATH I55
J 0
(275 875);
DISPLAY 0.872340 (275 875);
PAINT AQUA (275 875);
DISPLAY INVISIBLE (275 875);
FORCEADD Q_CAP..1
(1225 525);
FORCEPROP 1 LAST PART_NUMBER CH6103KEA00
J 0
(1275 375);
DISPLAY 0.978723 (1275 375);
DISPLAY INVISIBLE (1275 375);
FORCEPROP 1 LAST MATERIAL X6S
J 0
(1275 425);
DISPLAY 0.978723 (1275 425);
FORCEPROP 1 LAST VOLTAGE 16V
J 0
(1275 525);
DISPLAY 0.978723 (1275 525);
FORCEPROP 1 LAST TOLERANCE 10%
J 0
(1275 475);
DISPLAY 0.978723 (1275 475);
FORCEPROP 1 LAST VALUE 10UF
J 0
(1275 575);
DISPLAY 0.978723 (1275 575);
FORCEPROP 1 LAST PACK_TYPE C0805
J 0
(1275 325);
DISPLAY 0.978723 (1275 325);
FORCEPROP 1 LAST $LOCATION C79
J 0
(1275 625);
DISPLAY 0.978723 (1275 625);
FORCEPROP 1 LASTPIN (1225 625) $PN 1
J 0
(1235 605);
DISPLAY 0.787234 (1235 605);
FORCEPROP 1 LASTPIN (1225 425) $PN 2
J 0
(1235 405);
DISPLAY 0.787234 (1235 405);
FORCEPROP 2 LAST CDS_LIB pure_quanta
J 0
(1225 525);
PAINT MONO (1225 525);
DISPLAY INVISIBLE (1225 525);
FORCEPROP 1 LAST PATH I56
J 0
(1275 675);
DISPLAY 0.978723 (1275 675);
PAINT WHITE (1275 675);
DISPLAY INVISIBLE (1275 675);
FORCEPROP 1 LAST $LOCATION C79
J 0
(1275 725);
DISPLAY 1.021277 (1275 725);
DISPLAY INVISIBLE (1275 725);
FORCEPROP 2 LAST CDS_LOCATION C79
J 0
(1275 725);
DISPLAY 1.021277 (1275 725);
DISPLAY INVISIBLE (1275 725);
FORCEPROP 2 LAST $SEC 1
J 0
(1275 725);
DISPLAY 0.680851 (1275 725);
PAINT MONO (1275 725);
DISPLAY INVISIBLE (1275 725);
FORCEPROP 2 LAST CDS_SEC 1
J 0
(1275 725);
DISPLAY 1.021277 (1275 725);
DISPLAY INVISIBLE (1275 725);
FORCEADD VCC_CORE..1
(1225 850);
FORCEPROP 3 LASTPIN (1225 800) SIG_NAME P12V_S3_AUX_CPU1_NVDIMM\g
J 0
(1235 810);
DISPLAY 0.659574 (1235 810);
PAINT MONO (1235 810);
DISPLAY INVISIBLE (1235 810);
FORCEPROP 1 LAST HDL_POWER P12V_S3_AUX_CPU1_NVDIMM
J 1
(1225 900);
DISPLAY 1.148936 (1225 900);
PAINT GREEN (1225 900);
FORCEPROP 2 LAST CDS_LIB logical_power
J 0
(1225 850);
PAINT MONO (1225 850);
DISPLAY INVISIBLE (1225 850);
FORCEPROP 1 LAST PATH I57
J 0
(1275 875);
DISPLAY 0.872340 (1275 875);
PAINT AQUA (1275 875);
DISPLAY INVISIBLE (1275 875);
FORCEADD UNIVERSAL_GND..1
(1850 150);
FORCEPROP 3 LASTPIN (1850 200) SIG_NAME GND\g
J 0
(1860 210);
DISPLAY 0.659574 (1860 210);
PAINT MONO (1860 210);
DISPLAY INVISIBLE (1860 210);
FORCEPROP 1 LAST PATH I58
J 0
(1925 150);
DISPLAY 0.872340 (1925 150);
PAINT AQUA (1925 150);
DISPLAY INVISIBLE (1925 150);
FORCEPROP 1 LAST HDL_POWER GND
J 1
(1875 75);
DISPLAY 0.872340 (1875 75);
PAINT GREEN (1875 75);
DISPLAY INVISIBLE (1875 75);
FORCEPROP 2 LAST CDS_LIB logical_power
J 0
(1850 150);
PAINT MONO (1850 150);
DISPLAY INVISIBLE (1850 150);
FORCEADD Q_CAP..1
(1850 525);
FORCEPROP 1 LAST PART_NUMBER CH6103KEA00
J 0
(1900 375);
DISPLAY 0.978723 (1900 375);
DISPLAY INVISIBLE (1900 375);
FORCEPROP 1 LAST MATERIAL X6S
J 0
(1900 425);
DISPLAY 0.978723 (1900 425);
FORCEPROP 1 LAST VALUE 10UF
J 0
(1900 575);
DISPLAY 0.978723 (1900 575);
FORCEPROP 1 LAST PACK_TYPE C0805
J 0
(1900 325);
DISPLAY 0.978723 (1900 325);
FORCEPROP 1 LAST VOLTAGE 16V
J 0
(1900 525);
DISPLAY 0.978723 (1900 525);
FORCEPROP 1 LAST TOLERANCE 10%
J 0
(1900 475);
DISPLAY 0.978723 (1900 475);
FORCEPROP 1 LAST $LOCATION C80
J 0
(1900 625);
DISPLAY 0.978723 (1900 625);
FORCEPROP 1 LASTPIN (1850 625) $PN 1
J 0
(1860 605);
DISPLAY 0.787234 (1860 605);
FORCEPROP 1 LASTPIN (1850 425) $PN 2
J 0
(1860 405);
DISPLAY 0.787234 (1860 405);
FORCEPROP 2 LAST CDS_LIB pure_quanta
J 0
(1850 525);
PAINT MONO (1850 525);
DISPLAY INVISIBLE (1850 525);
FORCEPROP 1 LAST PATH I59
J 0
(1900 675);
DISPLAY 0.978723 (1900 675);
PAINT WHITE (1900 675);
DISPLAY INVISIBLE (1900 675);
FORCEPROP 1 LAST $LOCATION C80
J 0
(1900 725);
DISPLAY 1.021277 (1900 725);
DISPLAY INVISIBLE (1900 725);
FORCEPROP 2 LAST CDS_LOCATION C80
J 0
(1900 725);
DISPLAY 1.021277 (1900 725);
DISPLAY INVISIBLE (1900 725);
FORCEPROP 2 LAST $SEC 1
J 0
(1900 725);
DISPLAY 0.680851 (1900 725);
PAINT MONO (1900 725);
DISPLAY INVISIBLE (1900 725);
FORCEPROP 2 LAST CDS_SEC 1
J 0
(1900 725);
DISPLAY 1.021277 (1900 725);
DISPLAY INVISIBLE (1900 725);
FORCEADD OFFPAGE..3
R 2
(-4075 1550);
FORCEPROP 2 LAST $XR0 114 
J 0
(-4355 1550);
DISPLAY 0.638298 (-4355 1550);
PAINT MONO (-4355 1550);
FORCEPROP 2 LAST CDS_LIB standard
J 0
(-4075 1550);
PAINT MONO (-4075 1550);
DISPLAY INVISIBLE (-4075 1550);
FORCEPROP 1 LAST OFFPAGE TRUE
J 2
(-4400 1425);
DISPLAY 0.872340 (-4400 1425);
DISPLAY INVISIBLE (-4400 1425);
FORCEPROP 1 LAST COMMENT_BODY TRUE
J 2
(-4025 1450);
DISPLAY 0.872340 (-4025 1450);
PAINT GREEN (-4025 1450);
DISPLAY INVISIBLE (-4025 1450);
FORCEPROP 2 LAST PATH I6
J 0
(-4025 1625);
DISPLAY 1.021277 (-4025 1625);
DISPLAY INVISIBLE (-4025 1625);
FORCEADD UNIVERSAL_GND..1
(2925 700);
FORCEPROP 3 LASTPIN (2925 750) SIG_NAME GND\g
J 0
(2935 760);
DISPLAY 0.659574 (2935 760);
PAINT MONO (2935 760);
DISPLAY INVISIBLE (2935 760);
FORCEPROP 1 LAST PATH I60
J 0
(3000 700);
DISPLAY 0.872340 (3000 700);
PAINT AQUA (3000 700);
DISPLAY INVISIBLE (3000 700);
FORCEPROP 1 LAST HDL_POWER GND
J 1
(2950 625);
DISPLAY 0.872340 (2950 625);
PAINT GREEN (2950 625);
DISPLAY INVISIBLE (2950 625);
FORCEPROP 2 LAST CDS_LIB logical_power
J 0
(2925 700);
PAINT MONO (2925 700);
DISPLAY INVISIBLE (2925 700);
FORCEADD UNIVERSAL_GND..1
(4625 700);
FORCEPROP 3 LASTPIN (4625 750) SIG_NAME GND\g
J 0
(4635 760);
DISPLAY 0.659574 (4635 760);
PAINT MONO (4635 760);
DISPLAY INVISIBLE (4635 760);
FORCEPROP 1 LAST PATH I62
J 0
(4700 700);
DISPLAY 0.872340 (4700 700);
PAINT AQUA (4700 700);
DISPLAY INVISIBLE (4700 700);
FORCEPROP 1 LAST HDL_POWER GND
J 1
(4650 625);
DISPLAY 0.872340 (4650 625);
PAINT GREEN (4650 625);
DISPLAY INVISIBLE (4650 625);
FORCEPROP 2 LAST CDS_LIB logical_power
J 0
(4625 700);
PAINT MONO (4625 700);
DISPLAY INVISIBLE (4625 700);
FORCEADD TAP..1
(-1500 1200);
FORCEPROP 3 LASTPIN (-1550 1200) SIG_NAME M_G_CPU1_SB_DQ<0>
J 0
(-1540 1210);
DISPLAY 0.659574 (-1540 1210);
PAINT MONO (-1540 1210);
DISPLAY INVISIBLE (-1540 1210);
FORCEPROP 1 LASTPIN (-1550 1200) BN 0
J 0
(-1562 1208);
DISPLAY 0.680851 (-1562 1208);
PAINT GREEN (-1562 1208);
FORCEPROP 2 LAST CDS_LIB standard
J 0
(-1500 1200);
PAINT MONO (-1500 1200);
DISPLAY INVISIBLE (-1500 1200);
FORCEPROP 1 LAST BODY_TYPE PLUMBING
J 0
(-1500 1250);
DISPLAY 0.872340 (-1500 1250);
PAINT GREEN (-1500 1250);
DISPLAY INVISIBLE (-1500 1250);
FORCEPROP 1 LAST HDL_TAP TRUE
J 0
(-1175 1075);
DISPLAY 0.872340 (-1175 1075);
DISPLAY INVISIBLE (-1175 1075);
FORCEPROP 1 LAST PATH I63
J 0
(-1502 1200);
DISPLAY 0.872340 (-1502 1200);
PAINT GREEN (-1502 1200);
DISPLAY INVISIBLE (-1502 1200);
FORCEADD TAP..1
(-1500 1300);
FORCEPROP 3 LASTPIN (-1550 1300) SIG_NAME M_G_CPU1_SB_DQ<2>
J 0
(-1540 1310);
DISPLAY 0.659574 (-1540 1310);
PAINT MONO (-1540 1310);
DISPLAY INVISIBLE (-1540 1310);
FORCEPROP 1 LASTPIN (-1550 1300) BN 2
J 0
(-1562 1308);
DISPLAY 0.680851 (-1562 1308);
PAINT GREEN (-1562 1308);
FORCEPROP 2 LAST CDS_LIB standard
J 0
(-1500 1300);
PAINT MONO (-1500 1300);
DISPLAY INVISIBLE (-1500 1300);
FORCEPROP 1 LAST BODY_TYPE PLUMBING
J 0
(-1500 1350);
DISPLAY 0.872340 (-1500 1350);
PAINT GREEN (-1500 1350);
DISPLAY INVISIBLE (-1500 1350);
FORCEPROP 1 LAST HDL_TAP TRUE
J 0
(-1175 1175);
DISPLAY 0.872340 (-1175 1175);
DISPLAY INVISIBLE (-1175 1175);
FORCEPROP 1 LAST PATH I64
J 0
(-1502 1300);
DISPLAY 0.872340 (-1502 1300);
PAINT GREEN (-1502 1300);
DISPLAY INVISIBLE (-1502 1300);
FORCEADD TAP..1
(-1500 1250);
FORCEPROP 3 LASTPIN (-1550 1250) SIG_NAME M_G_CPU1_SB_DQ<1>
J 0
(-1540 1260);
DISPLAY 0.659574 (-1540 1260);
PAINT MONO (-1540 1260);
DISPLAY INVISIBLE (-1540 1260);
FORCEPROP 1 LASTPIN (-1550 1250) BN 1
J 0
(-1562 1258);
DISPLAY 0.680851 (-1562 1258);
PAINT GREEN (-1562 1258);
FORCEPROP 2 LAST CDS_LIB standard
J 0
(-1500 1250);
PAINT MONO (-1500 1250);
DISPLAY INVISIBLE (-1500 1250);
FORCEPROP 1 LAST BODY_TYPE PLUMBING
J 0
(-1500 1300);
DISPLAY 0.872340 (-1500 1300);
PAINT GREEN (-1500 1300);
DISPLAY INVISIBLE (-1500 1300);
FORCEPROP 1 LAST HDL_TAP TRUE
J 0
(-1175 1125);
DISPLAY 0.872340 (-1175 1125);
DISPLAY INVISIBLE (-1175 1125);
FORCEPROP 1 LAST PATH I65
J 0
(-1502 1250);
DISPLAY 0.872340 (-1502 1250);
PAINT GREEN (-1502 1250);
DISPLAY INVISIBLE (-1502 1250);
FORCEADD TAP..1
(-1500 1400);
FORCEPROP 3 LASTPIN (-1550 1400) SIG_NAME M_G_CPU1_SB_DQ<4>
J 0
(-1540 1410);
DISPLAY 0.659574 (-1540 1410);
PAINT MONO (-1540 1410);
DISPLAY INVISIBLE (-1540 1410);
FORCEPROP 1 LASTPIN (-1550 1400) BN 4
J 0
(-1562 1408);
DISPLAY 0.680851 (-1562 1408);
PAINT GREEN (-1562 1408);
FORCEPROP 2 LAST CDS_LIB standard
J 0
(-1500 1400);
PAINT MONO (-1500 1400);
DISPLAY INVISIBLE (-1500 1400);
FORCEPROP 1 LAST BODY_TYPE PLUMBING
J 0
(-1500 1450);
DISPLAY 0.872340 (-1500 1450);
PAINT GREEN (-1500 1450);
DISPLAY INVISIBLE (-1500 1450);
FORCEPROP 1 LAST HDL_TAP TRUE
J 0
(-1175 1275);
DISPLAY 0.872340 (-1175 1275);
DISPLAY INVISIBLE (-1175 1275);
FORCEPROP 1 LAST PATH I66
J 0
(-1502 1400);
DISPLAY 0.872340 (-1502 1400);
PAINT GREEN (-1502 1400);
DISPLAY INVISIBLE (-1502 1400);
FORCEADD TAP..1
(-1500 1450);
FORCEPROP 3 LASTPIN (-1550 1450) SIG_NAME M_G_CPU1_SB_DQ<5>
J 0
(-1540 1460);
DISPLAY 0.659574 (-1540 1460);
PAINT MONO (-1540 1460);
DISPLAY INVISIBLE (-1540 1460);
FORCEPROP 1 LASTPIN (-1550 1450) BN 5
J 0
(-1562 1458);
DISPLAY 0.680851 (-1562 1458);
PAINT GREEN (-1562 1458);
FORCEPROP 2 LAST CDS_LIB standard
J 0
(-1500 1450);
PAINT MONO (-1500 1450);
DISPLAY INVISIBLE (-1500 1450);
FORCEPROP 1 LAST BODY_TYPE PLUMBING
J 0
(-1500 1500);
DISPLAY 0.872340 (-1500 1500);
PAINT GREEN (-1500 1500);
DISPLAY INVISIBLE (-1500 1500);
FORCEPROP 1 LAST HDL_TAP TRUE
J 0
(-1175 1325);
DISPLAY 0.872340 (-1175 1325);
DISPLAY INVISIBLE (-1175 1325);
FORCEPROP 1 LAST PATH I67
J 0
(-1502 1450);
DISPLAY 0.872340 (-1502 1450);
PAINT GREEN (-1502 1450);
DISPLAY INVISIBLE (-1502 1450);
FORCEADD TAP..1
(-1500 1350);
FORCEPROP 3 LASTPIN (-1550 1350) SIG_NAME M_G_CPU1_SB_DQ<3>
J 0
(-1540 1360);
DISPLAY 0.659574 (-1540 1360);
PAINT MONO (-1540 1360);
DISPLAY INVISIBLE (-1540 1360);
FORCEPROP 1 LASTPIN (-1550 1350) BN 3
J 0
(-1562 1358);
DISPLAY 0.680851 (-1562 1358);
PAINT GREEN (-1562 1358);
FORCEPROP 2 LAST CDS_LIB standard
J 0
(-1500 1350);
PAINT MONO (-1500 1350);
DISPLAY INVISIBLE (-1500 1350);
FORCEPROP 1 LAST BODY_TYPE PLUMBING
J 0
(-1500 1400);
DISPLAY 0.872340 (-1500 1400);
PAINT GREEN (-1500 1400);
DISPLAY INVISIBLE (-1500 1400);
FORCEPROP 1 LAST HDL_TAP TRUE
J 0
(-1175 1225);
DISPLAY 0.872340 (-1175 1225);
DISPLAY INVISIBLE (-1175 1225);
FORCEPROP 1 LAST PATH I68
J 0
(-1502 1350);
DISPLAY 0.872340 (-1502 1350);
PAINT GREEN (-1502 1350);
DISPLAY INVISIBLE (-1502 1350);
FORCEADD TAP..1
(-1500 1550);
FORCEPROP 3 LASTPIN (-1550 1550) SIG_NAME M_G_CPU1_SB_DQ<7>
J 0
(-1540 1560);
DISPLAY 0.659574 (-1540 1560);
PAINT MONO (-1540 1560);
DISPLAY INVISIBLE (-1540 1560);
FORCEPROP 1 LASTPIN (-1550 1550) BN 7
J 0
(-1562 1558);
DISPLAY 0.680851 (-1562 1558);
PAINT GREEN (-1562 1558);
FORCEPROP 2 LAST CDS_LIB standard
J 0
(-1500 1550);
PAINT MONO (-1500 1550);
DISPLAY INVISIBLE (-1500 1550);
FORCEPROP 1 LAST BODY_TYPE PLUMBING
J 0
(-1500 1600);
DISPLAY 0.872340 (-1500 1600);
PAINT GREEN (-1500 1600);
DISPLAY INVISIBLE (-1500 1600);
FORCEPROP 1 LAST HDL_TAP TRUE
J 0
(-1175 1425);
DISPLAY 0.872340 (-1175 1425);
DISPLAY INVISIBLE (-1175 1425);
FORCEPROP 1 LAST PATH I69
J 0
(-1502 1550);
DISPLAY 0.872340 (-1502 1550);
PAINT GREEN (-1502 1550);
DISPLAY INVISIBLE (-1502 1550);
FORCEADD TAP..1
(-1500 1500);
FORCEPROP 3 LASTPIN (-1550 1500) SIG_NAME M_G_CPU1_SB_DQ<6>
J 0
(-1540 1510);
DISPLAY 0.659574 (-1540 1510);
PAINT MONO (-1540 1510);
DISPLAY INVISIBLE (-1540 1510);
FORCEPROP 1 LASTPIN (-1550 1500) BN 6
J 0
(-1562 1508);
DISPLAY 0.680851 (-1562 1508);
PAINT GREEN (-1562 1508);
FORCEPROP 2 LAST CDS_LIB standard
J 0
(-1500 1500);
PAINT MONO (-1500 1500);
DISPLAY INVISIBLE (-1500 1500);
FORCEPROP 1 LAST BODY_TYPE PLUMBING
J 0
(-1500 1550);
DISPLAY 0.872340 (-1500 1550);
PAINT GREEN (-1500 1550);
DISPLAY INVISIBLE (-1500 1550);
FORCEPROP 1 LAST HDL_TAP TRUE
J 0
(-1175 1375);
DISPLAY 0.872340 (-1175 1375);
DISPLAY INVISIBLE (-1175 1375);
FORCEPROP 1 LAST PATH I70
J 0
(-1502 1500);
DISPLAY 0.872340 (-1502 1500);
PAINT GREEN (-1502 1500);
DISPLAY INVISIBLE (-1502 1500);
FORCEADD TAP..1
(-1500 1700);
FORCEPROP 3 LASTPIN (-1550 1700) SIG_NAME M_G_CPU1_SB_DQ<10>
J 0
(-1540 1710);
DISPLAY 0.659574 (-1540 1710);
PAINT MONO (-1540 1710);
DISPLAY INVISIBLE (-1540 1710);
FORCEPROP 1 LASTPIN (-1550 1700) BN 10
J 0
(-1562 1708);
DISPLAY 0.680851 (-1562 1708);
PAINT GREEN (-1562 1708);
FORCEPROP 2 LAST CDS_LIB standard
J 0
(-1500 1700);
PAINT MONO (-1500 1700);
DISPLAY INVISIBLE (-1500 1700);
FORCEPROP 1 LAST BODY_TYPE PLUMBING
J 0
(-1500 1750);
DISPLAY 0.872340 (-1500 1750);
PAINT GREEN (-1500 1750);
DISPLAY INVISIBLE (-1500 1750);
FORCEPROP 1 LAST HDL_TAP TRUE
J 0
(-1175 1575);
DISPLAY 0.872340 (-1175 1575);
DISPLAY INVISIBLE (-1175 1575);
FORCEPROP 1 LAST PATH I71
J 0
(-1502 1700);
DISPLAY 0.872340 (-1502 1700);
PAINT GREEN (-1502 1700);
DISPLAY INVISIBLE (-1502 1700);
FORCEADD TAP..1
(-1500 1650);
FORCEPROP 3 LASTPIN (-1550 1650) SIG_NAME M_G_CPU1_SB_DQ<9>
J 0
(-1540 1660);
DISPLAY 0.659574 (-1540 1660);
PAINT MONO (-1540 1660);
DISPLAY INVISIBLE (-1540 1660);
FORCEPROP 1 LASTPIN (-1550 1650) BN 9
J 0
(-1562 1658);
DISPLAY 0.680851 (-1562 1658);
PAINT GREEN (-1562 1658);
FORCEPROP 2 LAST CDS_LIB standard
J 0
(-1500 1650);
PAINT MONO (-1500 1650);
DISPLAY INVISIBLE (-1500 1650);
FORCEPROP 1 LAST BODY_TYPE PLUMBING
J 0
(-1500 1700);
DISPLAY 0.872340 (-1500 1700);
PAINT GREEN (-1500 1700);
DISPLAY INVISIBLE (-1500 1700);
FORCEPROP 1 LAST HDL_TAP TRUE
J 0
(-1175 1525);
DISPLAY 0.872340 (-1175 1525);
DISPLAY INVISIBLE (-1175 1525);
FORCEPROP 1 LAST PATH I72
J 0
(-1502 1650);
DISPLAY 0.872340 (-1502 1650);
PAINT GREEN (-1502 1650);
DISPLAY INVISIBLE (-1502 1650);
FORCEADD TAP..1
(-1500 1600);
FORCEPROP 3 LASTPIN (-1550 1600) SIG_NAME M_G_CPU1_SB_DQ<8>
J 0
(-1540 1610);
DISPLAY 0.659574 (-1540 1610);
PAINT MONO (-1540 1610);
DISPLAY INVISIBLE (-1540 1610);
FORCEPROP 1 LASTPIN (-1550 1600) BN 8
J 0
(-1562 1608);
DISPLAY 0.680851 (-1562 1608);
PAINT GREEN (-1562 1608);
FORCEPROP 2 LAST CDS_LIB standard
J 0
(-1500 1600);
PAINT MONO (-1500 1600);
DISPLAY INVISIBLE (-1500 1600);
FORCEPROP 1 LAST BODY_TYPE PLUMBING
J 0
(-1500 1650);
DISPLAY 0.872340 (-1500 1650);
PAINT GREEN (-1500 1650);
DISPLAY INVISIBLE (-1500 1650);
FORCEPROP 1 LAST HDL_TAP TRUE
J 0
(-1175 1475);
DISPLAY 0.872340 (-1175 1475);
DISPLAY INVISIBLE (-1175 1475);
FORCEPROP 1 LAST PATH I73
J 0
(-1502 1600);
DISPLAY 0.872340 (-1502 1600);
PAINT GREEN (-1502 1600);
DISPLAY INVISIBLE (-1502 1600);
FORCEADD TAP..1
(-1500 1750);
FORCEPROP 3 LASTPIN (-1550 1750) SIG_NAME M_G_CPU1_SB_DQ<11>
J 0
(-1540 1760);
DISPLAY 0.659574 (-1540 1760);
PAINT MONO (-1540 1760);
DISPLAY INVISIBLE (-1540 1760);
FORCEPROP 1 LASTPIN (-1550 1750) BN 11
J 0
(-1562 1758);
DISPLAY 0.680851 (-1562 1758);
PAINT GREEN (-1562 1758);
FORCEPROP 2 LAST CDS_LIB standard
J 0
(-1500 1750);
PAINT MONO (-1500 1750);
DISPLAY INVISIBLE (-1500 1750);
FORCEPROP 1 LAST BODY_TYPE PLUMBING
J 0
(-1500 1800);
DISPLAY 0.872340 (-1500 1800);
PAINT GREEN (-1500 1800);
DISPLAY INVISIBLE (-1500 1800);
FORCEPROP 1 LAST HDL_TAP TRUE
J 0
(-1175 1625);
DISPLAY 0.872340 (-1175 1625);
DISPLAY INVISIBLE (-1175 1625);
FORCEPROP 1 LAST PATH I74
J 0
(-1502 1750);
DISPLAY 0.872340 (-1502 1750);
PAINT GREEN (-1502 1750);
DISPLAY INVISIBLE (-1502 1750);
FORCEADD TAP..1
(-1500 1800);
FORCEPROP 3 LASTPIN (-1550 1800) SIG_NAME M_G_CPU1_SB_DQ<12>
J 0
(-1540 1810);
DISPLAY 0.659574 (-1540 1810);
PAINT MONO (-1540 1810);
DISPLAY INVISIBLE (-1540 1810);
FORCEPROP 1 LASTPIN (-1550 1800) BN 12
J 0
(-1562 1808);
DISPLAY 0.680851 (-1562 1808);
PAINT GREEN (-1562 1808);
FORCEPROP 2 LAST CDS_LIB standard
J 0
(-1500 1800);
PAINT MONO (-1500 1800);
DISPLAY INVISIBLE (-1500 1800);
FORCEPROP 1 LAST BODY_TYPE PLUMBING
J 0
(-1500 1850);
DISPLAY 0.872340 (-1500 1850);
PAINT GREEN (-1500 1850);
DISPLAY INVISIBLE (-1500 1850);
FORCEPROP 1 LAST HDL_TAP TRUE
J 0
(-1175 1675);
DISPLAY 0.872340 (-1175 1675);
DISPLAY INVISIBLE (-1175 1675);
FORCEPROP 1 LAST PATH I75
J 0
(-1502 1800);
DISPLAY 0.872340 (-1502 1800);
PAINT GREEN (-1502 1800);
DISPLAY INVISIBLE (-1502 1800);
FORCEADD TAP..1
(-1500 1950);
FORCEPROP 3 LASTPIN (-1550 1950) SIG_NAME M_G_CPU1_SB_DQ<15>
J 0
(-1540 1960);
DISPLAY 0.659574 (-1540 1960);
PAINT MONO (-1540 1960);
DISPLAY INVISIBLE (-1540 1960);
FORCEPROP 1 LASTPIN (-1550 1950) BN 15
J 0
(-1562 1958);
DISPLAY 0.680851 (-1562 1958);
PAINT GREEN (-1562 1958);
FORCEPROP 2 LAST CDS_LIB standard
J 0
(-1500 1950);
PAINT MONO (-1500 1950);
DISPLAY INVISIBLE (-1500 1950);
FORCEPROP 1 LAST BODY_TYPE PLUMBING
J 0
(-1500 2000);
DISPLAY 0.872340 (-1500 2000);
PAINT GREEN (-1500 2000);
DISPLAY INVISIBLE (-1500 2000);
FORCEPROP 1 LAST HDL_TAP TRUE
J 0
(-1175 1825);
DISPLAY 0.872340 (-1175 1825);
DISPLAY INVISIBLE (-1175 1825);
FORCEPROP 1 LAST PATH I76
J 0
(-1502 1950);
DISPLAY 0.872340 (-1502 1950);
PAINT GREEN (-1502 1950);
DISPLAY INVISIBLE (-1502 1950);
FORCEADD TAP..1
(-1500 1900);
FORCEPROP 3 LASTPIN (-1550 1900) SIG_NAME M_G_CPU1_SB_DQ<14>
J 0
(-1540 1910);
DISPLAY 0.659574 (-1540 1910);
PAINT MONO (-1540 1910);
DISPLAY INVISIBLE (-1540 1910);
FORCEPROP 1 LASTPIN (-1550 1900) BN 14
J 0
(-1562 1908);
DISPLAY 0.680851 (-1562 1908);
PAINT GREEN (-1562 1908);
FORCEPROP 2 LAST CDS_LIB standard
J 0
(-1500 1900);
PAINT MONO (-1500 1900);
DISPLAY INVISIBLE (-1500 1900);
FORCEPROP 1 LAST BODY_TYPE PLUMBING
J 0
(-1500 1950);
DISPLAY 0.872340 (-1500 1950);
PAINT GREEN (-1500 1950);
DISPLAY INVISIBLE (-1500 1950);
FORCEPROP 1 LAST HDL_TAP TRUE
J 0
(-1175 1775);
DISPLAY 0.872340 (-1175 1775);
DISPLAY INVISIBLE (-1175 1775);
FORCEPROP 1 LAST PATH I77
J 0
(-1502 1900);
DISPLAY 0.872340 (-1502 1900);
PAINT GREEN (-1502 1900);
DISPLAY INVISIBLE (-1502 1900);
FORCEADD TAP..1
(-1500 1850);
FORCEPROP 3 LASTPIN (-1550 1850) SIG_NAME M_G_CPU1_SB_DQ<13>
J 0
(-1540 1860);
DISPLAY 0.659574 (-1540 1860);
PAINT MONO (-1540 1860);
DISPLAY INVISIBLE (-1540 1860);
FORCEPROP 1 LASTPIN (-1550 1850) BN 13
J 0
(-1562 1858);
DISPLAY 0.680851 (-1562 1858);
PAINT GREEN (-1562 1858);
FORCEPROP 2 LAST CDS_LIB standard
J 0
(-1500 1850);
PAINT MONO (-1500 1850);
DISPLAY INVISIBLE (-1500 1850);
FORCEPROP 1 LAST BODY_TYPE PLUMBING
J 0
(-1500 1900);
DISPLAY 0.872340 (-1500 1900);
PAINT GREEN (-1500 1900);
DISPLAY INVISIBLE (-1500 1900);
FORCEPROP 1 LAST HDL_TAP TRUE
J 0
(-1175 1725);
DISPLAY 0.872340 (-1175 1725);
DISPLAY INVISIBLE (-1175 1725);
FORCEPROP 1 LAST PATH I78
J 0
(-1502 1850);
DISPLAY 0.872340 (-1502 1850);
PAINT GREEN (-1502 1850);
DISPLAY INVISIBLE (-1502 1850);
FORCEADD TAP..1
(-1500 2000);
FORCEPROP 3 LASTPIN (-1550 2000) SIG_NAME M_G_CPU1_SB_DQ<16>
J 0
(-1540 2010);
DISPLAY 0.659574 (-1540 2010);
PAINT MONO (-1540 2010);
DISPLAY INVISIBLE (-1540 2010);
FORCEPROP 1 LASTPIN (-1550 2000) BN 16
J 0
(-1562 2008);
DISPLAY 0.680851 (-1562 2008);
PAINT GREEN (-1562 2008);
FORCEPROP 2 LAST CDS_LIB standard
J 0
(-1500 2000);
PAINT MONO (-1500 2000);
DISPLAY INVISIBLE (-1500 2000);
FORCEPROP 1 LAST BODY_TYPE PLUMBING
J 0
(-1500 2050);
DISPLAY 0.872340 (-1500 2050);
PAINT GREEN (-1500 2050);
DISPLAY INVISIBLE (-1500 2050);
FORCEPROP 1 LAST HDL_TAP TRUE
J 0
(-1175 1875);
DISPLAY 0.872340 (-1175 1875);
DISPLAY INVISIBLE (-1175 1875);
FORCEPROP 1 LAST PATH I79
J 0
(-1502 2000);
DISPLAY 0.872340 (-1502 2000);
PAINT GREEN (-1502 2000);
DISPLAY INVISIBLE (-1502 2000);
FORCEADD OFFPAGE..1
(-3950 1900);
FORCEPROP 2 LAST $XR0 111 
J 0
(-4202 1900);
DISPLAY 0.638298 (-4202 1900);
PAINT MONO (-4202 1900);
FORCEPROP 2 LAST CDS_LIB standard
J 0
(-3950 1900);
PAINT MONO (-3950 1900);
DISPLAY INVISIBLE (-3950 1900);
FORCEPROP 1 LAST OFFPAGE TRUE
J 0
(-3625 1775);
DISPLAY 0.872340 (-3625 1775);
DISPLAY INVISIBLE (-3625 1775);
FORCEPROP 1 LAST COMMENT_BODY TRUE
J 0
(-3825 1800);
DISPLAY 0.872340 (-3825 1800);
PAINT GREEN (-3825 1800);
DISPLAY INVISIBLE (-3825 1800);
FORCEPROP 2 LAST PATH I8
J 0
(-3900 1975);
DISPLAY 1.021277 (-3900 1975);
DISPLAY INVISIBLE (-3900 1975);
FORCEADD TAP..1
(-1500 2050);
FORCEPROP 3 LASTPIN (-1550 2050) SIG_NAME M_G_CPU1_SB_DQ<17>
J 0
(-1540 2060);
DISPLAY 0.659574 (-1540 2060);
PAINT MONO (-1540 2060);
DISPLAY INVISIBLE (-1540 2060);
FORCEPROP 1 LASTPIN (-1550 2050) BN 17
J 0
(-1562 2058);
DISPLAY 0.680851 (-1562 2058);
PAINT GREEN (-1562 2058);
FORCEPROP 2 LAST CDS_LIB standard
J 0
(-1500 2050);
PAINT MONO (-1500 2050);
DISPLAY INVISIBLE (-1500 2050);
FORCEPROP 1 LAST BODY_TYPE PLUMBING
J 0
(-1500 2100);
DISPLAY 0.872340 (-1500 2100);
PAINT GREEN (-1500 2100);
DISPLAY INVISIBLE (-1500 2100);
FORCEPROP 1 LAST HDL_TAP TRUE
J 0
(-1175 1925);
DISPLAY 0.872340 (-1175 1925);
DISPLAY INVISIBLE (-1175 1925);
FORCEPROP 1 LAST PATH I80
J 0
(-1502 2050);
DISPLAY 0.872340 (-1502 2050);
PAINT GREEN (-1502 2050);
DISPLAY INVISIBLE (-1502 2050);
FORCEADD TAP..1
(-1500 2150);
FORCEPROP 3 LASTPIN (-1550 2150) SIG_NAME M_G_CPU1_SB_DQ<19>
J 0
(-1540 2160);
DISPLAY 0.659574 (-1540 2160);
PAINT MONO (-1540 2160);
DISPLAY INVISIBLE (-1540 2160);
FORCEPROP 1 LASTPIN (-1550 2150) BN 19
J 0
(-1562 2158);
DISPLAY 0.680851 (-1562 2158);
PAINT GREEN (-1562 2158);
FORCEPROP 2 LAST CDS_LIB standard
J 0
(-1500 2150);
PAINT MONO (-1500 2150);
DISPLAY INVISIBLE (-1500 2150);
FORCEPROP 1 LAST BODY_TYPE PLUMBING
J 0
(-1500 2200);
DISPLAY 0.872340 (-1500 2200);
PAINT GREEN (-1500 2200);
DISPLAY INVISIBLE (-1500 2200);
FORCEPROP 1 LAST HDL_TAP TRUE
J 0
(-1175 2025);
DISPLAY 0.872340 (-1175 2025);
DISPLAY INVISIBLE (-1175 2025);
FORCEPROP 1 LAST PATH I81
J 0
(-1502 2150);
DISPLAY 0.872340 (-1502 2150);
PAINT GREEN (-1502 2150);
DISPLAY INVISIBLE (-1502 2150);
FORCEADD TAP..1
(-1500 2200);
FORCEPROP 3 LASTPIN (-1550 2200) SIG_NAME M_G_CPU1_SB_DQ<20>
J 0
(-1540 2210);
DISPLAY 0.659574 (-1540 2210);
PAINT MONO (-1540 2210);
DISPLAY INVISIBLE (-1540 2210);
FORCEPROP 1 LASTPIN (-1550 2200) BN 20
J 0
(-1562 2208);
DISPLAY 0.680851 (-1562 2208);
PAINT GREEN (-1562 2208);
FORCEPROP 2 LAST CDS_LIB standard
J 0
(-1500 2200);
PAINT MONO (-1500 2200);
DISPLAY INVISIBLE (-1500 2200);
FORCEPROP 1 LAST BODY_TYPE PLUMBING
J 0
(-1500 2250);
DISPLAY 0.872340 (-1500 2250);
PAINT GREEN (-1500 2250);
DISPLAY INVISIBLE (-1500 2250);
FORCEPROP 1 LAST HDL_TAP TRUE
J 0
(-1175 2075);
DISPLAY 0.872340 (-1175 2075);
DISPLAY INVISIBLE (-1175 2075);
FORCEPROP 1 LAST PATH I82
J 0
(-1502 2200);
DISPLAY 0.872340 (-1502 2200);
PAINT GREEN (-1502 2200);
DISPLAY INVISIBLE (-1502 2200);
FORCEADD TAP..1
(-1500 2100);
FORCEPROP 3 LASTPIN (-1550 2100) SIG_NAME M_G_CPU1_SB_DQ<18>
J 0
(-1540 2110);
DISPLAY 0.659574 (-1540 2110);
PAINT MONO (-1540 2110);
DISPLAY INVISIBLE (-1540 2110);
FORCEPROP 1 LASTPIN (-1550 2100) BN 18
J 0
(-1562 2108);
DISPLAY 0.680851 (-1562 2108);
PAINT GREEN (-1562 2108);
FORCEPROP 2 LAST CDS_LIB standard
J 0
(-1500 2100);
PAINT MONO (-1500 2100);
DISPLAY INVISIBLE (-1500 2100);
FORCEPROP 1 LAST BODY_TYPE PLUMBING
J 0
(-1500 2150);
DISPLAY 0.872340 (-1500 2150);
PAINT GREEN (-1500 2150);
DISPLAY INVISIBLE (-1500 2150);
FORCEPROP 1 LAST HDL_TAP TRUE
J 0
(-1175 1975);
DISPLAY 0.872340 (-1175 1975);
DISPLAY INVISIBLE (-1175 1975);
FORCEPROP 1 LAST PATH I83
J 0
(-1502 2100);
DISPLAY 0.872340 (-1502 2100);
PAINT GREEN (-1502 2100);
DISPLAY INVISIBLE (-1502 2100);
FORCEADD TAP..1
(-1500 2350);
FORCEPROP 3 LASTPIN (-1550 2350) SIG_NAME M_G_CPU1_SB_DQ<23>
J 0
(-1540 2360);
DISPLAY 0.659574 (-1540 2360);
PAINT MONO (-1540 2360);
DISPLAY INVISIBLE (-1540 2360);
FORCEPROP 1 LASTPIN (-1550 2350) BN 23
J 0
(-1562 2358);
DISPLAY 0.680851 (-1562 2358);
PAINT GREEN (-1562 2358);
FORCEPROP 2 LAST CDS_LIB standard
J 0
(-1500 2350);
DISPLAY INVISIBLE (-1500 2350);
FORCEPROP 1 LAST BODY_TYPE PLUMBING
J 0
(-1500 2400);
DISPLAY 0.872340 (-1500 2400);
PAINT GREEN (-1500 2400);
DISPLAY INVISIBLE (-1500 2400);
FORCEPROP 1 LAST HDL_TAP TRUE
J 0
(-1175 2225);
DISPLAY 0.872340 (-1175 2225);
DISPLAY INVISIBLE (-1175 2225);
FORCEPROP 1 LAST PATH I84
J 0
(-1502 2350);
DISPLAY 0.872340 (-1502 2350);
PAINT GREEN (-1502 2350);
DISPLAY INVISIBLE (-1502 2350);
FORCEADD TAP..1
(-1500 2300);
FORCEPROP 3 LASTPIN (-1550 2300) SIG_NAME M_G_CPU1_SB_DQ<22>
J 0
(-1540 2310);
DISPLAY 0.659574 (-1540 2310);
PAINT MONO (-1540 2310);
DISPLAY INVISIBLE (-1540 2310);
FORCEPROP 1 LASTPIN (-1550 2300) BN 22
J 0
(-1562 2308);
DISPLAY 0.680851 (-1562 2308);
PAINT GREEN (-1562 2308);
FORCEPROP 2 LAST CDS_LIB standard
J 0
(-1500 2300);
DISPLAY INVISIBLE (-1500 2300);
FORCEPROP 1 LAST BODY_TYPE PLUMBING
J 0
(-1500 2350);
DISPLAY 0.872340 (-1500 2350);
PAINT GREEN (-1500 2350);
DISPLAY INVISIBLE (-1500 2350);
FORCEPROP 1 LAST HDL_TAP TRUE
J 0
(-1175 2175);
DISPLAY 0.872340 (-1175 2175);
DISPLAY INVISIBLE (-1175 2175);
FORCEPROP 1 LAST PATH I85
J 0
(-1502 2300);
DISPLAY 0.872340 (-1502 2300);
PAINT GREEN (-1502 2300);
DISPLAY INVISIBLE (-1502 2300);
FORCEADD TAP..1
(-1500 2250);
FORCEPROP 3 LASTPIN (-1550 2250) SIG_NAME M_G_CPU1_SB_DQ<21>
J 0
(-1540 2260);
DISPLAY 0.659574 (-1540 2260);
PAINT MONO (-1540 2260);
DISPLAY INVISIBLE (-1540 2260);
FORCEPROP 1 LASTPIN (-1550 2250) BN 21
J 0
(-1562 2258);
DISPLAY 0.680851 (-1562 2258);
PAINT GREEN (-1562 2258);
FORCEPROP 2 LAST CDS_LIB standard
J 0
(-1500 2250);
PAINT MONO (-1500 2250);
DISPLAY INVISIBLE (-1500 2250);
FORCEPROP 1 LAST BODY_TYPE PLUMBING
J 0
(-1500 2300);
DISPLAY 0.872340 (-1500 2300);
PAINT GREEN (-1500 2300);
DISPLAY INVISIBLE (-1500 2300);
FORCEPROP 1 LAST HDL_TAP TRUE
J 0
(-1175 2125);
DISPLAY 0.872340 (-1175 2125);
DISPLAY INVISIBLE (-1175 2125);
FORCEPROP 1 LAST PATH I86
J 0
(-1502 2250);
DISPLAY 0.872340 (-1502 2250);
PAINT GREEN (-1502 2250);
DISPLAY INVISIBLE (-1502 2250);
FORCEADD TAP..1
(-1500 2400);
FORCEPROP 3 LASTPIN (-1550 2400) SIG_NAME M_G_CPU1_SB_DQ<24>
J 0
(-1540 2410);
DISPLAY 0.659574 (-1540 2410);
PAINT MONO (-1540 2410);
DISPLAY INVISIBLE (-1540 2410);
FORCEPROP 1 LASTPIN (-1550 2400) BN 24
J 0
(-1562 2408);
DISPLAY 0.680851 (-1562 2408);
PAINT GREEN (-1562 2408);
FORCEPROP 2 LAST CDS_LIB standard
J 0
(-1500 2400);
DISPLAY INVISIBLE (-1500 2400);
FORCEPROP 1 LAST BODY_TYPE PLUMBING
J 0
(-1500 2450);
DISPLAY 0.872340 (-1500 2450);
PAINT GREEN (-1500 2450);
DISPLAY INVISIBLE (-1500 2450);
FORCEPROP 1 LAST HDL_TAP TRUE
J 0
(-1175 2275);
DISPLAY 0.872340 (-1175 2275);
DISPLAY INVISIBLE (-1175 2275);
FORCEPROP 1 LAST PATH I87
J 0
(-1502 2400);
DISPLAY 0.872340 (-1502 2400);
PAINT GREEN (-1502 2400);
DISPLAY INVISIBLE (-1502 2400);
FORCEADD TAP..1
(-1500 2450);
FORCEPROP 3 LASTPIN (-1550 2450) SIG_NAME M_G_CPU1_SB_DQ<25>
J 0
(-1540 2460);
DISPLAY 0.659574 (-1540 2460);
PAINT MONO (-1540 2460);
DISPLAY INVISIBLE (-1540 2460);
FORCEPROP 1 LASTPIN (-1550 2450) BN 25
J 0
(-1562 2458);
DISPLAY 0.680851 (-1562 2458);
PAINT GREEN (-1562 2458);
FORCEPROP 2 LAST CDS_LIB standard
J 0
(-1500 2450);
DISPLAY INVISIBLE (-1500 2450);
FORCEPROP 1 LAST BODY_TYPE PLUMBING
J 0
(-1500 2500);
DISPLAY 0.872340 (-1500 2500);
PAINT GREEN (-1500 2500);
DISPLAY INVISIBLE (-1500 2500);
FORCEPROP 1 LAST HDL_TAP TRUE
J 0
(-1175 2325);
DISPLAY 0.872340 (-1175 2325);
DISPLAY INVISIBLE (-1175 2325);
FORCEPROP 1 LAST PATH I88
J 0
(-1502 2450);
DISPLAY 0.872340 (-1502 2450);
PAINT GREEN (-1502 2450);
DISPLAY INVISIBLE (-1502 2450);
FORCEADD TAP..1
(-1500 2500);
FORCEPROP 3 LASTPIN (-1550 2500) SIG_NAME M_G_CPU1_SB_DQ<26>
J 0
(-1540 2510);
DISPLAY 0.659574 (-1540 2510);
PAINT MONO (-1540 2510);
DISPLAY INVISIBLE (-1540 2510);
FORCEPROP 1 LASTPIN (-1550 2500) BN 26
J 0
(-1562 2508);
DISPLAY 0.680851 (-1562 2508);
PAINT GREEN (-1562 2508);
FORCEPROP 2 LAST CDS_LIB standard
J 0
(-1500 2500);
DISPLAY INVISIBLE (-1500 2500);
FORCEPROP 1 LAST BODY_TYPE PLUMBING
J 0
(-1500 2550);
DISPLAY 0.872340 (-1500 2550);
PAINT GREEN (-1500 2550);
DISPLAY INVISIBLE (-1500 2550);
FORCEPROP 1 LAST HDL_TAP TRUE
J 0
(-1175 2375);
DISPLAY 0.872340 (-1175 2375);
DISPLAY INVISIBLE (-1175 2375);
FORCEPROP 1 LAST PATH I89
J 0
(-1502 2500);
DISPLAY 0.872340 (-1502 2500);
PAINT GREEN (-1502 2500);
DISPLAY INVISIBLE (-1502 2500);
FORCEADD OFFPAGE..1
(-3950 1850);
FORCEPROP 2 LAST $XR7 113 
J 0
(-4442 1886);
DISPLAY 0.638298 (-4442 1886);
PAINT MONO (-4442 1886);
FORCEPROP 2 LAST $XR6 112 
J 0
(-4322 1886);
DISPLAY 0.638298 (-4322 1886);
PAINT MONO (-4322 1886);
FORCEPROP 2 LAST $XR5 110 
J 0
(-4442 1814);
DISPLAY 0.638298 (-4442 1814);
PAINT MONO (-4442 1814);
FORCEPROP 2 LAST $XR4 109 
J 0
(-4322 1814);
DISPLAY 0.638298 (-4322 1814);
PAINT MONO (-4322 1814);
FORCEPROP 2 LAST $XR3 108 
J 0
(-4202 1814);
DISPLAY 0.638298 (-4202 1814);
PAINT MONO (-4202 1814);
FORCEPROP 2 LAST $XR2 107 
J 0
(-4442 1850);
DISPLAY 0.638298 (-4442 1850);
PAINT MONO (-4442 1850);
FORCEPROP 2 LAST $XR1 106 
J 0
(-4322 1850);
DISPLAY 0.638298 (-4322 1850);
PAINT MONO (-4322 1850);
FORCEPROP 2 LAST $XR0 230 
J 0
(-4202 1850);
DISPLAY 0.638298 (-4202 1850);
PAINT MONO (-4202 1850);
FORCEPROP 2 LAST CDS_LIB standard
J 0
(-3950 1850);
PAINT MONO (-3950 1850);
DISPLAY INVISIBLE (-3950 1850);
FORCEPROP 1 LAST OFFPAGE TRUE
J 0
(-3625 1725);
DISPLAY 0.872340 (-3625 1725);
DISPLAY INVISIBLE (-3625 1725);
FORCEPROP 1 LAST COMMENT_BODY TRUE
J 0
(-3825 1750);
DISPLAY 0.872340 (-3825 1750);
PAINT GREEN (-3825 1750);
DISPLAY INVISIBLE (-3825 1750);
FORCEPROP 2 LAST PATH I9
J 0
(-3900 1925);
DISPLAY 1.021277 (-3900 1925);
DISPLAY INVISIBLE (-3900 1925);
FORCEADD TAP..1
(-1500 2600);
FORCEPROP 3 LASTPIN (-1550 2600) SIG_NAME M_G_CPU1_SB_DQ<28>
J 0
(-1540 2610);
DISPLAY 0.659574 (-1540 2610);
PAINT MONO (-1540 2610);
DISPLAY INVISIBLE (-1540 2610);
FORCEPROP 1 LASTPIN (-1550 2600) BN 28
J 0
(-1562 2608);
DISPLAY 0.680851 (-1562 2608);
PAINT GREEN (-1562 2608);
FORCEPROP 2 LAST CDS_LIB standard
J 0
(-1500 2600);
DISPLAY INVISIBLE (-1500 2600);
FORCEPROP 1 LAST BODY_TYPE PLUMBING
J 0
(-1500 2650);
DISPLAY 0.872340 (-1500 2650);
PAINT GREEN (-1500 2650);
DISPLAY INVISIBLE (-1500 2650);
FORCEPROP 1 LAST HDL_TAP TRUE
J 0
(-1175 2475);
DISPLAY 0.872340 (-1175 2475);
DISPLAY INVISIBLE (-1175 2475);
FORCEPROP 1 LAST PATH I90
J 0
(-1502 2600);
DISPLAY 0.872340 (-1502 2600);
PAINT GREEN (-1502 2600);
DISPLAY INVISIBLE (-1502 2600);
FORCEADD TAP..1
(-1500 2550);
FORCEPROP 3 LASTPIN (-1550 2550) SIG_NAME M_G_CPU1_SB_DQ<27>
J 0
(-1540 2560);
DISPLAY 0.659574 (-1540 2560);
PAINT MONO (-1540 2560);
DISPLAY INVISIBLE (-1540 2560);
FORCEPROP 1 LASTPIN (-1550 2550) BN 27
J 0
(-1562 2558);
DISPLAY 0.680851 (-1562 2558);
PAINT GREEN (-1562 2558);
FORCEPROP 2 LAST CDS_LIB standard
J 0
(-1500 2550);
DISPLAY INVISIBLE (-1500 2550);
FORCEPROP 1 LAST BODY_TYPE PLUMBING
J 0
(-1500 2600);
DISPLAY 0.872340 (-1500 2600);
PAINT GREEN (-1500 2600);
DISPLAY INVISIBLE (-1500 2600);
FORCEPROP 1 LAST HDL_TAP TRUE
J 0
(-1175 2425);
DISPLAY 0.872340 (-1175 2425);
DISPLAY INVISIBLE (-1175 2425);
FORCEPROP 1 LAST PATH I91
J 0
(-1502 2550);
DISPLAY 0.872340 (-1502 2550);
PAINT GREEN (-1502 2550);
DISPLAY INVISIBLE (-1502 2550);
FORCEADD TAP..1
(-1500 2700);
FORCEPROP 3 LASTPIN (-1550 2700) SIG_NAME M_G_CPU1_SB_DQ<30>
J 0
(-1540 2710);
DISPLAY 0.659574 (-1540 2710);
PAINT MONO (-1540 2710);
DISPLAY INVISIBLE (-1540 2710);
FORCEPROP 1 LASTPIN (-1550 2700) BN 30
J 0
(-1562 2708);
DISPLAY 0.680851 (-1562 2708);
PAINT GREEN (-1562 2708);
FORCEPROP 2 LAST CDS_LIB standard
J 0
(-1500 2700);
DISPLAY INVISIBLE (-1500 2700);
FORCEPROP 1 LAST BODY_TYPE PLUMBING
J 0
(-1500 2750);
DISPLAY 0.872340 (-1500 2750);
PAINT GREEN (-1500 2750);
DISPLAY INVISIBLE (-1500 2750);
FORCEPROP 1 LAST HDL_TAP TRUE
J 0
(-1175 2575);
DISPLAY 0.872340 (-1175 2575);
DISPLAY INVISIBLE (-1175 2575);
FORCEPROP 1 LAST PATH I92
J 0
(-1502 2700);
DISPLAY 0.872340 (-1502 2700);
PAINT GREEN (-1502 2700);
DISPLAY INVISIBLE (-1502 2700);
FORCEADD TAP..1
(-1500 2650);
FORCEPROP 3 LASTPIN (-1550 2650) SIG_NAME M_G_CPU1_SB_DQ<29>
J 0
(-1540 2660);
DISPLAY 0.659574 (-1540 2660);
PAINT MONO (-1540 2660);
DISPLAY INVISIBLE (-1540 2660);
FORCEPROP 1 LASTPIN (-1550 2650) BN 29
J 0
(-1562 2658);
DISPLAY 0.680851 (-1562 2658);
PAINT GREEN (-1562 2658);
FORCEPROP 2 LAST CDS_LIB standard
J 0
(-1500 2650);
DISPLAY INVISIBLE (-1500 2650);
FORCEPROP 1 LAST BODY_TYPE PLUMBING
J 0
(-1500 2700);
DISPLAY 0.872340 (-1500 2700);
PAINT GREEN (-1500 2700);
DISPLAY INVISIBLE (-1500 2700);
FORCEPROP 1 LAST HDL_TAP TRUE
J 0
(-1175 2525);
DISPLAY 0.872340 (-1175 2525);
DISPLAY INVISIBLE (-1175 2525);
FORCEPROP 1 LAST PATH I93
J 0
(-1502 2650);
DISPLAY 0.872340 (-1502 2650);
PAINT GREEN (-1502 2650);
DISPLAY INVISIBLE (-1502 2650);
FORCEADD TAP..1
(-1500 2850);
FORCEPROP 3 LASTPIN (-1550 2850) SIG_NAME M_G_CPU1_SA_DQ<0>
J 0
(-1540 2860);
DISPLAY 0.659574 (-1540 2860);
PAINT MONO (-1540 2860);
DISPLAY INVISIBLE (-1540 2860);
FORCEPROP 1 LASTPIN (-1550 2850) BN 0
J 0
(-1562 2858);
DISPLAY 0.680851 (-1562 2858);
PAINT GREEN (-1562 2858);
FORCEPROP 2 LAST CDS_LIB standard
J 0
(-1500 2850);
PAINT MONO (-1500 2850);
DISPLAY INVISIBLE (-1500 2850);
FORCEPROP 1 LAST BODY_TYPE PLUMBING
J 0
(-1500 2900);
DISPLAY 0.872340 (-1500 2900);
PAINT GREEN (-1500 2900);
DISPLAY INVISIBLE (-1500 2900);
FORCEPROP 1 LAST HDL_TAP TRUE
J 0
(-1175 2725);
DISPLAY 0.872340 (-1175 2725);
DISPLAY INVISIBLE (-1175 2725);
FORCEPROP 1 LAST PATH I94
J 0
(-1502 2850);
DISPLAY 0.872340 (-1502 2850);
PAINT GREEN (-1502 2850);
DISPLAY INVISIBLE (-1502 2850);
FORCEADD TAP..1
(-1500 2750);
FORCEPROP 3 LASTPIN (-1550 2750) SIG_NAME M_G_CPU1_SB_DQ<31>
J 0
(-1540 2760);
DISPLAY 0.659574 (-1540 2760);
PAINT MONO (-1540 2760);
DISPLAY INVISIBLE (-1540 2760);
FORCEPROP 1 LASTPIN (-1550 2750) BN 31
J 0
(-1562 2758);
DISPLAY 0.680851 (-1562 2758);
PAINT GREEN (-1562 2758);
FORCEPROP 2 LAST CDS_LIB standard
J 0
(-1500 2750);
DISPLAY INVISIBLE (-1500 2750);
FORCEPROP 1 LAST BODY_TYPE PLUMBING
J 0
(-1500 2800);
DISPLAY 0.872340 (-1500 2800);
PAINT GREEN (-1500 2800);
DISPLAY INVISIBLE (-1500 2800);
FORCEPROP 1 LAST HDL_TAP TRUE
J 0
(-1175 2625);
DISPLAY 0.872340 (-1175 2625);
DISPLAY INVISIBLE (-1175 2625);
FORCEPROP 1 LAST PATH I95
J 0
(-1502 2750);
DISPLAY 0.872340 (-1502 2750);
PAINT GREEN (-1502 2750);
DISPLAY INVISIBLE (-1502 2750);
FORCEADD TAP..1
(-1500 2950);
FORCEPROP 3 LASTPIN (-1550 2950) SIG_NAME M_G_CPU1_SA_DQ<2>
J 0
(-1540 2960);
DISPLAY 0.659574 (-1540 2960);
PAINT MONO (-1540 2960);
DISPLAY INVISIBLE (-1540 2960);
FORCEPROP 1 LASTPIN (-1550 2950) BN 2
J 0
(-1562 2958);
DISPLAY 0.680851 (-1562 2958);
PAINT GREEN (-1562 2958);
FORCEPROP 2 LAST CDS_LIB standard
J 0
(-1500 2950);
PAINT MONO (-1500 2950);
DISPLAY INVISIBLE (-1500 2950);
FORCEPROP 1 LAST BODY_TYPE PLUMBING
J 0
(-1500 3000);
DISPLAY 0.872340 (-1500 3000);
PAINT GREEN (-1500 3000);
DISPLAY INVISIBLE (-1500 3000);
FORCEPROP 1 LAST HDL_TAP TRUE
J 0
(-1175 2825);
DISPLAY 0.872340 (-1175 2825);
DISPLAY INVISIBLE (-1175 2825);
FORCEPROP 1 LAST PATH I96
J 0
(-1502 2950);
DISPLAY 0.872340 (-1502 2950);
PAINT GREEN (-1502 2950);
DISPLAY INVISIBLE (-1502 2950);
FORCEADD TAP..1
(-1500 2900);
FORCEPROP 3 LASTPIN (-1550 2900) SIG_NAME M_G_CPU1_SA_DQ<1>
J 0
(-1540 2910);
DISPLAY 0.659574 (-1540 2910);
PAINT MONO (-1540 2910);
DISPLAY INVISIBLE (-1540 2910);
FORCEPROP 1 LASTPIN (-1550 2900) BN 1
J 0
(-1562 2908);
DISPLAY 0.680851 (-1562 2908);
PAINT GREEN (-1562 2908);
FORCEPROP 2 LAST CDS_LIB standard
J 0
(-1500 2900);
PAINT MONO (-1500 2900);
DISPLAY INVISIBLE (-1500 2900);
FORCEPROP 1 LAST BODY_TYPE PLUMBING
J 0
(-1500 2950);
DISPLAY 0.872340 (-1500 2950);
PAINT GREEN (-1500 2950);
DISPLAY INVISIBLE (-1500 2950);
FORCEPROP 1 LAST HDL_TAP TRUE
J 0
(-1175 2775);
DISPLAY 0.872340 (-1175 2775);
DISPLAY INVISIBLE (-1175 2775);
FORCEPROP 1 LAST PATH I97
J 0
(-1502 2900);
DISPLAY 0.872340 (-1502 2900);
PAINT GREEN (-1502 2900);
DISPLAY INVISIBLE (-1502 2900);
FORCEADD TAP..1
(-1500 3050);
FORCEPROP 3 LASTPIN (-1550 3050) SIG_NAME M_G_CPU1_SA_DQ<4>
J 0
(-1540 3060);
DISPLAY 0.659574 (-1540 3060);
PAINT MONO (-1540 3060);
DISPLAY INVISIBLE (-1540 3060);
FORCEPROP 1 LASTPIN (-1550 3050) BN 4
J 0
(-1562 3058);
DISPLAY 0.680851 (-1562 3058);
PAINT GREEN (-1562 3058);
FORCEPROP 2 LAST CDS_LIB standard
J 0
(-1500 3050);
PAINT MONO (-1500 3050);
DISPLAY INVISIBLE (-1500 3050);
FORCEPROP 1 LAST BODY_TYPE PLUMBING
J 0
(-1500 3100);
DISPLAY 0.872340 (-1500 3100);
PAINT GREEN (-1500 3100);
DISPLAY INVISIBLE (-1500 3100);
FORCEPROP 1 LAST HDL_TAP TRUE
J 0
(-1175 2925);
DISPLAY 0.872340 (-1175 2925);
DISPLAY INVISIBLE (-1175 2925);
FORCEPROP 1 LAST PATH I98
J 0
(-1502 3050);
DISPLAY 0.872340 (-1502 3050);
PAINT GREEN (-1502 3050);
DISPLAY INVISIBLE (-1502 3050);
FORCEADD TAP..1
(-1500 3100);
FORCEPROP 3 LASTPIN (-1550 3100) SIG_NAME M_G_CPU1_SA_DQ<5>
J 0
(-1540 3110);
DISPLAY 0.659574 (-1540 3110);
PAINT MONO (-1540 3110);
DISPLAY INVISIBLE (-1540 3110);
FORCEPROP 1 LASTPIN (-1550 3100) BN 5
J 0
(-1562 3108);
DISPLAY 0.680851 (-1562 3108);
PAINT GREEN (-1562 3108);
FORCEPROP 2 LAST CDS_LIB standard
J 0
(-1500 3100);
PAINT MONO (-1500 3100);
DISPLAY INVISIBLE (-1500 3100);
FORCEPROP 1 LAST BODY_TYPE PLUMBING
J 0
(-1500 3150);
DISPLAY 0.872340 (-1500 3150);
PAINT GREEN (-1500 3150);
DISPLAY INVISIBLE (-1500 3150);
FORCEPROP 1 LAST HDL_TAP TRUE
J 0
(-1175 2975);
DISPLAY 0.872340 (-1175 2975);
DISPLAY INVISIBLE (-1175 2975);
FORCEPROP 1 LAST PATH I99
J 0
(-1502 3100);
DISPLAY 0.872340 (-1502 3100);
PAINT GREEN (-1502 3100);
DISPLAY INVISIBLE (-1502 3100);
FORCEADD CAD_NOTE..1
(350 -50);
FORCEPROP 0 LAST S1 PLACE THE BYPASS CAPS CLOSE TO DIMM
J 0
(225 -175);
DISPLAY 1.021277 (225 -175);
PAINT WHITE (225 -175);
FORCEPROP 2 LAST CDS_LIB logical_power
J 0
(350 -50);
PAINT MONO (350 -50);
DISPLAY INVISIBLE (350 -50);
FORCEPROP 1 LAST COMMENT_BODY TRUE
J 0
(375 50);
DISPLAY 0.978723 (375 50);
DISPLAY INVISIBLE (375 50);
FORCEADD QUANTA_TITLE_BLOCK_C..1
(4825 -1350);
FORCEPROP 0 LAST CDS_CON_LAST_MODIFIED Fri Aug 25 14:01:32 2023
J 0
(2940 -1335);
PAINT MONO (2940 -1335);
DISPLAY INVISIBLE (2940 -1335);
FORCEPROP 1 LAST CUSTOM_TXT_CDS <CON_LAST_MODIFIED>
J 0
(2940 -1335);
DISPLAY 0.978723 (2940 -1335);
FORCEPROP 2 LAST CUSTOM_TXT_CDS <XR_PAGE_TITLE>
J 0
(-3065 3900);
DISPLAY 0.638298 (-3065 3900);
PAINT PINK (-3065 3900);
DISPLAY INVISIBLE (-3065 3900);
FORCEPROP 2 LAST CUSTOM_TXT_CDS <Q_NUMBER>
J 0
(3422 -1247);
DISPLAY 1.212766 (3422 -1247);
FORCEPROP 1 LAST CUSTOM_TXT_CDS <NAME_2>
J 0
(1650 -1300);
FORCEPROP 1 LAST CUSTOM_TXT_CDS <NAME_1>
J 0
(1650 -1175);
FORCEPROP 1 LAST CUSTOM_TXT_CDS <Q_PROJ>
J 0
(2443 -1248);
DISPLAY 1.212766 (2443 -1248);
FORCEPROP 1 LAST CUSTOM_TXT_CDS <Q_REV>
J 0
(4641 -1247);
DISPLAY 1.212766 (4641 -1247);
FORCEPROP 1 LAST CUSTOM_TXT_CDS <CON_PAGE_NUM> OF <CON_TOTAL_PAGES>
J 0
(4379 -1332);
DISPLAY 0.978723 (4379 -1332);
FORCEPROP 1 LAST Q_TITLE DDR5 - CPU1 CHG DIMM2(BLACK)
J 0
(-4541 -1324);
DISPLAY 2.446809 (-4541 -1324);
PAINT GREEN (-4541 -1324);
FORCEPROP 1 LAST Q_DEPT 
J 1
(1062 -1301);
DISPLAY 1.957447 (1062 -1301);
PAINT GREEN (1062 -1301);
FORCEPROP 2 LAST CDS_XR_PAGE_TITLE CR-111 : @S9S_MB_2U_LIB.S9S_MB_2U(SCH_1):PAGE111
J 0
(-3065 3900);
DISPLAY 0.638298 (-3065 3900);
PAINT PINK (-3065 3900);
DISPLAY INVISIBLE (-3065 3900);
FORCEPROP 1 LAST COMMENT_BODY TRUE
J 0
(4837 -1363);
DISPLAY 0.978723 (4837 -1363);
PAINT GREEN (4837 -1363);
DISPLAY INVISIBLE (4837 -1363);
FORCEPROP 2 LAST PAGE_BORDER TRUE
J 0
(-3065 3900);
DISPLAY 0.638298 (-3065 3900);
PAINT PINK (-3065 3900);
DISPLAY INVISIBLE (-3065 3900);
FORCEPROP 1 LAST CDS_LMAN_SYM_OUTLINE -9475,6775,100,-125
J 0
(4825 -1350);
DISPLAY 0.468085 (4825 -1350);
PAINT GREEN (4825 -1350);
DISPLAY INVISIBLE (4825 -1350);
FORCEPROP 2 LAST CDS_LIB pure_quanta
J 0
(4825 -1350);
PAINT MONO (4825 -1350);
DISPLAY INVISIBLE (4825 -1350);
WIRE 17 -1 (-1450 4375)(-1450 4425);
WIRE 17 -1 (-1450 4325)(-1450 4375);
WIRE 17 -1 (-1450 4425)(-725 4425);
FORCEPROP 2 LAST SIG_NAME M_G_CPU1_SA_DQ<31:0>
J 0
(-1385 4435);
DISPLAY 0.680851 (-1385 4435);
PAINT WHITE (-1385 4435);
WIRE 17 -1 (-3200 2975)(-3200 3025);
WIRE 17 -1 (-3200 2925)(-3200 2975);
WIRE 17 -1 (-4025 3025)(-3200 3025);
FORCEPROP 2 LAST SIG_NAME M_G_CPU1_SA_CB<7:0>
J 0
(-3935 3035);
DISPLAY 0.680851 (-3935 3035);
PAINT WHITE (-3935 3035);
WIRE 17 -1 (-3200 2725)(-3200 2775);
WIRE 17 -1 (-3200 2675)(-3200 2725);
WIRE 17 -1 (-3200 2775)(-3200 2825);
WIRE 17 -1 (-3200 2825)(-3200 2875);
WIRE 17 -1 (-3200 2875)(-3200 2925);
WIRE 17 -1 (-3200 2525)(-3200 2575);
WIRE 17 -1 (-3200 2475)(-3200 2525);
WIRE 17 -1 (-4025 2575)(-3200 2575);
FORCEPROP 2 LAST SIG_NAME M_G_CPU1_SB_CB<7:0>
J 0
(-3935 2585);
DISPLAY 0.680851 (-3935 2585);
PAINT WHITE (-3935 2585);
WIRE 17 -1 (-3200 4125)(-3200 4175);
WIRE 17 -1 (-3200 4175)(-3200 4225);
WIRE 17 -1 (-3200 4225)(-3200 4275);
WIRE 17 -1 (-3200 4275)(-3200 4325);
WIRE 17 -1 (-3200 4325)(-3200 4375);
WIRE 17 -1 (-3200 4375)(-3200 4425);
WIRE 17 -1 (-4025 4425)(-3200 4425);
FORCEPROP 2 LAST SIG_NAME M_G_CPU1_SA_CA<6:0>
J 0
(-3935 4435);
DISPLAY 0.680851 (-3935 4435);
PAINT WHITE (-3935 4435);
WIRE 17 -1 (-3200 3725)(-3200 3775);
WIRE 17 -1 (-3200 3775)(-3200 3825);
WIRE 17 -1 (-3200 3825)(-3200 3875);
WIRE 17 -1 (-3200 3875)(-3200 3925);
WIRE 17 -1 (-3200 3925)(-3200 3975);
WIRE 17 -1 (-3200 3975)(-3200 4025);
WIRE 17 -1 (-4025 4025)(-3200 4025);
FORCEPROP 2 LAST SIG_NAME M_G_CPU1_SB_CA<6:0>
J 0
(-3935 4035);
DISPLAY 0.680851 (-3935 4035);
PAINT WHITE (-3935 4035);
WIRE 17 -1 (-3200 2425)(-3200 2475);
WIRE 17 -1 (-3200 2375)(-3200 2425);
WIRE 17 -1 (-3200 2325)(-3200 2375);
WIRE 17 -1 (-3200 2275)(-3200 2325);
WIRE 17 -1 (-3200 2225)(-3200 2275);
WIRE 17 -1 (-1450 4275)(-1450 4325);
WIRE 17 -1 (-1450 4225)(-1450 4275);
WIRE 17 -1 (-1450 4175)(-1450 4225);
WIRE 17 -1 (-1450 4125)(-1450 4175);
WIRE 17 -1 (-1450 4075)(-1450 4125);
WIRE 17 -1 (-1450 4025)(-1450 4075);
WIRE 17 -1 (-1450 3975)(-1450 4025);
WIRE 17 -1 (-1450 3925)(-1450 3975);
WIRE 17 -1 (-1450 3875)(-1450 3925);
WIRE 17 -1 (-1450 3825)(-1450 3875);
WIRE 17 -1 (-1450 3775)(-1450 3825);
WIRE 17 -1 (-1450 3725)(-1450 3775);
WIRE 17 -1 (-1450 3675)(-1450 3725);
WIRE 17 -1 (-1450 3625)(-1450 3675);
WIRE 17 -1 (-1450 3575)(-1450 3625);
WIRE 17 -1 (-1450 3525)(-1450 3575);
WIRE 17 -1 (-1450 3475)(-1450 3525);
WIRE 17 -1 (-1450 3425)(-1450 3475);
WIRE 17 -1 (-1450 3375)(-1450 3425);
WIRE 17 -1 (-1450 3325)(-1450 3375);
WIRE 17 -1 (-1450 3275)(-1450 3325);
WIRE 17 -1 (-1450 3225)(-1450 3275);
WIRE 17 -1 (-1450 3175)(-1450 3225);
WIRE 17 -1 (-1450 3125)(-1450 3175);
WIRE 17 -1 (-1450 3075)(-1450 3125);
WIRE 17 -1 (-1450 3025)(-1450 3075);
WIRE 17 -1 (-1450 2975)(-1450 3025);
WIRE 17 -1 (-1450 2925)(-1450 2975);
WIRE 17 -1 (-1450 2875)(-1450 2925);
WIRE 17 -1 (-1450 2725)(-1450 2775);
WIRE 17 -1 (-1450 2675)(-1450 2725);
WIRE 17 -1 (-1450 2775)(-725 2775);
FORCEPROP 2 LAST SIG_NAME M_G_CPU1_SB_DQ<31:0>
J 0
(-1385 2785);
DISPLAY 0.680851 (-1385 2785);
PAINT WHITE (-1385 2785);
WIRE 17 -1 (-1450 2625)(-1450 2675);
WIRE 17 -1 (-1450 2575)(-1450 2625);
WIRE 17 -1 (-1450 2525)(-1450 2575);
WIRE 17 -1 (-1450 2475)(-1450 2525);
WIRE 17 -1 (-1450 2425)(-1450 2475);
WIRE 17 -1 (-1450 2375)(-1450 2425);
WIRE 17 -1 (-1450 2325)(-1450 2375);
WIRE 17 -1 (-1450 2275)(-1450 2325);
WIRE 17 -1 (-1450 2225)(-1450 2275);
WIRE 17 -1 (-1450 2175)(-1450 2225);
WIRE 17 -1 (-1450 2125)(-1450 2175);
WIRE 17 -1 (-1450 2075)(-1450 2125);
WIRE 17 -1 (-1450 2025)(-1450 2075);
WIRE 17 -1 (-1450 1975)(-1450 2025);
WIRE 17 -1 (-1450 1925)(-1450 1975);
WIRE 17 -1 (-1450 1875)(-1450 1925);
WIRE 17 -1 (-1450 1825)(-1450 1875);
WIRE 17 -1 (-1450 1775)(-1450 1825);
WIRE 17 -1 (-1450 1725)(-1450 1775);
WIRE 17 -1 (-1450 1675)(-1450 1725);
WIRE 17 -1 (-1450 1625)(-1450 1675);
WIRE 17 -1 (-1450 1575)(-1450 1625);
WIRE 17 -1 (-1450 1525)(-1450 1575);
WIRE 17 -1 (-1450 1475)(-1450 1525);
WIRE 17 -1 (-1450 1425)(-1450 1475);
WIRE 17 -1 (-1450 1375)(-1450 1425);
WIRE 17 -1 (-1450 1325)(-1450 1375);
WIRE 17 -1 (-1450 1275)(-1450 1325);
WIRE 17 -1 (-1450 1225)(-1450 1275);
WIRE 17 -1 (1300 2475)(1300 2575);
WIRE 17 -1 (1300 2575)(1300 2675);
WIRE 17 -1 (1300 2675)(1300 2775);
WIRE 17 -1 (1300 2875)(1300 2775);
WIRE 17 -1 (1300 2875)(1300 2975);
WIRE 17 -1 (1300 2975)(1300 3075);
WIRE 17 -1 (1300 3075)(1300 3175);
WIRE 17 -1 (1300 3175)(1300 3275);
WIRE 17 -1 (1300 3275)(1300 3375);
WIRE 17 -1 (1300 3375)(2325 3375);
FORCEPROP 2 LAST SIG_NAME M_G_CPU1_SB_DQS_DP<9:0>
J 0
(1540 3385);
DISPLAY 0.680851 (1540 3385);
PAINT WHITE (1540 3385);
WIRE 17 -1 (1300 3525)(1300 3625);
WIRE 17 -1 (1300 3625)(1300 3725);
WIRE 17 -1 (1300 3725)(1300 3825);
WIRE 17 -1 (1300 3925)(1300 3825);
WIRE 17 -1 (1300 3925)(1300 4025);
WIRE 17 -1 (1300 4025)(1300 4125);
WIRE 17 -1 (1300 4125)(1300 4225);
WIRE 17 -1 (1300 4225)(1300 4325);
WIRE 17 -1 (1300 4325)(1300 4425);
WIRE 17 -1 (1300 4425)(2325 4425);
FORCEPROP 2 LAST SIG_NAME M_G_CPU1_SA_DQS_DP<9:0>
J 0
(1540 4435);
DISPLAY 0.680851 (1540 4435);
PAINT WHITE (1540 4435);
WIRE 17 -1 (1475 2425)(1475 2525);
WIRE 17 -1 (1475 2525)(1475 2625);
WIRE 17 -1 (1475 2625)(1475 2725);
WIRE 17 -1 (1475 2825)(1475 2725);
WIRE 17 -1 (1475 2825)(1475 2925);
WIRE 17 -1 (1475 2925)(1475 3025);
WIRE 17 -1 (1475 3025)(1475 3125);
WIRE 17 -1 (1475 3125)(1475 3225);
WIRE 17 -1 (1475 3225)(1475 3325);
WIRE 17 -1 (1475 3325)(2325 3325);
FORCEPROP 2 LAST SIG_NAME M_G_CPU1_SB_DQS_DN<9:0>
J 0
(1540 3335);
DISPLAY 0.680851 (1540 3335);
PAINT WHITE (1540 3335);
WIRE 17 -1 (1475 3475)(1475 3575);
WIRE 17 -1 (1475 3575)(1475 3675);
WIRE 17 -1 (1475 3675)(1475 3775);
WIRE 17 -1 (1475 3875)(1475 3775);
WIRE 17 -1 (1475 3875)(1475 3975);
WIRE 17 -1 (1475 3975)(1475 4075);
WIRE 17 -1 (1475 4075)(1475 4175);
WIRE 17 -1 (1475 4175)(1475 4275);
WIRE 17 -1 (1475 4275)(1475 4375);
WIRE 17 -1 (1475 4375)(2325 4375);
FORCEPROP 2 LAST SIG_NAME M_G_CPU1_SA_DQS_DN<9:0>
J 0
(1540 4385);
DISPLAY 0.680851 (1540 4385);
PAINT WHITE (1540 4385);
WIRE 16 -1 (1225 800)(1225 750);
WIRE 16 -1 (225 625)(225 800);
WIRE 16 -1 (2925 4900)(2925 4400);
WIRE 16 -1 (-3975 2225)(-3975 1950);
WIRE 16 -1 (4625 1050)(4625 750);
WIRE 16 -1 (4625 1100)(4625 1050);
WIRE 16 -1 (4375 1050)(4625 1050);
WIRE 16 -1 (2925 750)(2925 1150);
WIRE 16 -1 (1850 200)(1850 275);
WIRE 16 -1 (225 425)(225 200);
WIRE 16 -1 (-2925 75)(-2925 150);
WIRE 16 3135 (2475 1025)(-125 1025);
WIRE 16 3135 (2475 -275)(2475 1025);
WIRE 16 3135 (-125 1025)(-125 -275);
WIRE 16 3135 (-125 -275)(2475 -275);
WIRE 16 -1 (-4450 1675)(-4250 1675);
WIRE 16 -1 (-4450 1675)(-4450 1800);
WIRE 16 -1 (-2925 1800)(-4450 1800);
FORCEPROP 2 LAST SIG_NAME I3C_SPD_DDREFGH_CPU1_LVC1_SCL_R6
J 0
(-3937 1809);
DISPLAY 0.680851 (-3937 1809);
PAINT WHITE (-3937 1809);
WIRE 16 -1 (-3975 1950)(-2925 1950);
WIRE 16 -1 (-2925 1900)(-3900 1900);
FORCEPROP 2 LAST SIG_NAME PD_CHG_CPU1_DIMM2_SAA
J 0
(-3910 1910);
DISPLAY 0.680851 (-3910 1910);
PAINT WHITE (-3910 1910);
WIRE 16 -1 (-2925 1850)(-3900 1850);
FORCEPROP 2 LAST SIG_NAME I3C_SPD_DDREFGH_CPU1_LVC1_SDA
J 0
(-3910 1860);
DISPLAY 0.680851 (-3910 1860);
PAINT WHITE (-3910 1860);
WIRE 16 -1 (-2925 2050)(-4025 2050);
FORCEPROP 2 LAST SIG_NAME M_G_CPU1_ALERT_N
J 0
(-3937 2059);
DISPLAY 0.680851 (-3937 2059);
PAINT WHITE (-3937 2059);
WIRE 16 -1 (-3300 2100)(-2925 2100);
WIRE 16 -1 (-3300 2175)(-4025 2175);
FORCEPROP 2 LAST SIG_NAME RST_M_GH_CPU1_FPGA_N
J 0
(-3937 2184);
DISPLAY 0.680851 (-3937 2184);
PAINT WHITE (-3937 2184);
WIRE 16 -1 (-3300 2175)(-3300 2100);
WIRE 16 -1 (-2800 1625)(-2850 1625);
WIRE 16 -1 (-4050 1675)(-2800 1675);
FORCEPROP 2 LAST SIG_NAME I3C_SPD_DDREFGH_CPU1_LVC1_SCL
J 0
(-3885 1685);
DISPLAY 0.680851 (-3885 1685);
PAINT WHITE (-3885 1685);
WIRE 16 -1 (-2800 1675)(-2800 1625);
WIRE 16 -1 (-2925 1550)(-4025 1550);
FORCEPROP 2 LAST SIG_NAME PWRGD_CHG_CPU1_DIMM2
J 0
(-3937 1559);
DISPLAY 0.680851 (-3937 1559);
PAINT WHITE (-3937 1559);
WIRE 16 -1 (-2925 1450)(-4025 1450);
FORCEPROP 2 LAST SIG_NAME TP_CHG_CPU1_DIMM2_FRU_6
J 0
(-3937 1459);
DISPLAY 0.680851 (-3937 1459);
PAINT WHITE (-3937 1459);
WIRE 16 -1 (-1725 1650)(-1550 1650);
WIRE 16 -1 (1100 4350)(1375 4350);
WIRE 16 -1 (1100 4250)(1375 4250);
WIRE 16 -1 (1100 4150)(1375 4150);
WIRE 16 -1 (1100 4050)(1375 4050);
WIRE 16 -1 (1100 3950)(1375 3950);
WIRE 16 -1 (1100 3850)(1375 3850);
WIRE 16 -1 (1100 3750)(1375 3750);
WIRE 16 -1 (1100 3650)(1375 3650);
WIRE 16 -1 (1100 3550)(1375 3550);
WIRE 16 -1 (1100 3450)(1375 3450);
WIRE 16 -1 (1100 3300)(1375 3300);
WIRE 16 -1 (1100 3200)(1375 3200);
WIRE 16 -1 (1100 3100)(1375 3100);
WIRE 16 -1 (1100 3000)(1375 3000);
WIRE 16 -1 (1100 2900)(1375 2900);
WIRE 16 -1 (1100 2700)(1375 2700);
WIRE 16 -1 (1100 2800)(1375 2800);
WIRE 16 -1 (1100 2600)(1375 2600);
WIRE 16 -1 (1100 2500)(1375 2500);
WIRE 16 -1 (1100 2400)(1375 2400);
WIRE 16 -1 (1100 4400)(1200 4400);
WIRE 16 -1 (1100 4300)(1200 4300);
WIRE 16 -1 (1100 4200)(1200 4200);
WIRE 16 -1 (1100 4100)(1200 4100);
WIRE 16 -1 (1100 4000)(1200 4000);
WIRE 16 -1 (1100 3900)(1200 3900);
WIRE 16 -1 (1100 3800)(1200 3800);
WIRE 16 -1 (1100 3700)(1200 3700);
WIRE 16 -1 (1100 3600)(1200 3600);
WIRE 16 -1 (1100 3500)(1200 3500);
WIRE 16 -1 (1100 3350)(1200 3350);
WIRE 16 -1 (1100 3250)(1200 3250);
WIRE 16 -1 (1100 3150)(1200 3150);
WIRE 16 -1 (1100 3050)(1200 3050);
WIRE 16 -1 (1100 2950)(1200 2950);
WIRE 16 -1 (1100 2850)(1200 2850);
WIRE 16 -1 (1100 2750)(1200 2750);
WIRE 16 -1 (1100 2650)(1200 2650);
WIRE 16 -1 (1100 2550)(1200 2550);
WIRE 16 -1 (1100 2450)(1200 2450);
WIRE 16 -1 (-2925 1400)(-4025 1400);
FORCEPROP 2 LAST SIG_NAME TP_CHG_CPU1_DIMM2_FRU_5
J 0
(-3937 1409);
DISPLAY 0.680851 (-3937 1409);
PAINT WHITE (-3937 1409);
WIRE 16 -1 (3175 4300)(2925 4300);
WIRE 16 -1 (2925 4350)(2925 4300);
WIRE 16 -1 (2925 4350)(3175 4350);
WIRE 16 -1 (2925 4400)(2925 4350);
WIRE 16 -1 (3175 4400)(2925 4400);
WIRE 16 -1 (1225 750)(1225 625);
WIRE 16 -1 (1850 750)(1225 750);
WIRE 16 -1 (1850 625)(1850 750);
WIRE 16 -1 (1225 275)(1225 425);
WIRE 16 -1 (1850 275)(1225 275);
WIRE 16 -1 (1850 275)(1850 425);
WIRE 16 -1 (2925 1150)(3175 1150);
WIRE 16 -1 (2925 1150)(2925 1200);
WIRE 16 -1 (2925 1200)(3175 1200);
WIRE 16 -1 (2925 1200)(2925 1250);
WIRE 16 -1 (2925 1250)(3175 1250);
WIRE 16 -1 (2925 1250)(2925 1300);
WIRE 16 -1 (2925 1300)(3175 1300);
WIRE 16 -1 (2925 1300)(2925 1350);
WIRE 16 -1 (2925 1350)(3175 1350);
WIRE 16 -1 (2925 1350)(2925 1400);
WIRE 16 -1 (2925 1400)(3175 1400);
WIRE 16 -1 (2925 1400)(2925 1450);
WIRE 16 -1 (2925 1450)(3175 1450);
WIRE 16 -1 (2925 1450)(2925 1500);
WIRE 16 -1 (2925 1500)(3175 1500);
WIRE 16 -1 (2925 1500)(2925 1550);
WIRE 16 -1 (2925 1550)(3175 1550);
WIRE 16 -1 (2925 1550)(2925 1600);
WIRE 16 -1 (2925 1600)(3175 1600);
WIRE 16 -1 (2925 1600)(2925 1650);
WIRE 16 -1 (3175 1650)(2925 1650);
WIRE 16 -1 (2925 1650)(2925 1700);
WIRE 16 -1 (2925 1700)(3175 1700);
WIRE 16 -1 (2925 1700)(2925 1750);
WIRE 16 -1 (2925 1750)(3175 1750);
WIRE 16 -1 (2925 1750)(2925 1800);
WIRE 16 -1 (2925 1800)(3175 1800);
WIRE 16 -1 (2925 1800)(2925 1850);
WIRE 16 -1 (2925 1850)(3175 1850);
WIRE 16 -1 (2925 1850)(2925 1900);
WIRE 16 -1 (2925 1900)(3175 1900);
WIRE 16 -1 (2925 1900)(2925 1950);
WIRE 16 -1 (2925 1950)(3175 1950);
WIRE 16 -1 (2925 1950)(2925 2000);
WIRE 16 -1 (2925 2000)(3175 2000);
WIRE 16 -1 (2925 2000)(2925 2050);
WIRE 16 -1 (2925 2050)(3175 2050);
WIRE 16 -1 (2925 2050)(2925 2100);
WIRE 16 -1 (2925 2100)(3175 2100);
WIRE 16 -1 (2925 2100)(2925 2150);
WIRE 16 -1 (3175 2150)(2925 2150);
WIRE 16 -1 (2925 2150)(2925 2200);
WIRE 16 -1 (2925 2200)(3175 2200);
WIRE 16 -1 (2925 2200)(2925 2250);
WIRE 16 -1 (2925 2250)(3175 2250);
WIRE 16 -1 (2925 2250)(2925 2300);
WIRE 16 -1 (2925 2300)(3175 2300);
WIRE 16 -1 (2925 2300)(2925 2350);
WIRE 16 -1 (2925 2350)(3175 2350);
WIRE 16 -1 (2925 2350)(2925 2400);
WIRE 16 -1 (2925 2400)(3175 2400);
WIRE 16 -1 (2925 2400)(2925 2450);
WIRE 16 -1 (2925 2450)(3175 2450);
WIRE 16 -1 (2925 2450)(2925 2500);
WIRE 16 -1 (2925 2500)(3175 2500);
WIRE 16 -1 (2925 2500)(2925 2550);
WIRE 16 -1 (2925 2550)(3175 2550);
WIRE 16 -1 (2925 2550)(2925 2600);
WIRE 16 -1 (2925 2600)(3175 2600);
WIRE 16 -1 (2925 2600)(2925 2650);
WIRE 16 -1 (3175 2650)(2925 2650);
WIRE 16 -1 (2925 2650)(2925 2700);
WIRE 16 -1 (2925 2700)(3175 2700);
WIRE 16 -1 (2925 2700)(2925 2750);
WIRE 16 -1 (2925 2750)(3175 2750);
WIRE 16 -1 (2925 2750)(2925 2800);
WIRE 16 -1 (2925 2800)(3175 2800);
WIRE 16 -1 (2925 2800)(2925 2850);
WIRE 16 -1 (2925 2850)(3175 2850);
WIRE 16 -1 (2925 2850)(2925 2900);
WIRE 16 -1 (2925 2900)(3175 2900);
WIRE 16 -1 (2925 2900)(2925 2950);
WIRE 16 -1 (2925 2950)(3175 2950);
WIRE 16 -1 (2925 2950)(2925 3000);
WIRE 16 -1 (2925 3000)(3175 3000);
WIRE 16 -1 (2925 3000)(2925 3050);
WIRE 16 -1 (2925 3050)(3175 3050);
WIRE 16 -1 (2925 3050)(2925 3100);
WIRE 16 -1 (2925 3100)(3175 3100);
WIRE 16 -1 (2925 3100)(2925 3150);
WIRE 16 -1 (3175 3150)(2925 3150);
WIRE 16 -1 (2925 3150)(2925 3200);
WIRE 16 -1 (2925 3200)(3175 3200);
WIRE 16 -1 (2925 3200)(2925 3250);
WIRE 16 -1 (2925 3250)(3175 3250);
WIRE 16 -1 (2925 3250)(2925 3300);
WIRE 16 -1 (2925 3300)(3175 3300);
WIRE 16 -1 (2925 3300)(2925 3350);
WIRE 16 -1 (2925 3350)(3175 3350);
WIRE 16 -1 (2925 3350)(2925 3400);
WIRE 16 -1 (2925 3400)(3175 3400);
WIRE 16 -1 (2925 3400)(2925 3450);
WIRE 16 -1 (2925 3450)(3175 3450);
WIRE 16 -1 (2925 3450)(2925 3500);
WIRE 16 -1 (2925 3500)(3175 3500);
WIRE 16 -1 (2925 3500)(2925 3550);
WIRE 16 -1 (2925 3550)(3175 3550);
WIRE 16 -1 (2925 3550)(2925 3600);
WIRE 16 -1 (2925 3600)(3175 3600);
WIRE 16 -1 (2925 3600)(2925 3650);
WIRE 16 -1 (3175 3650)(2925 3650);
WIRE 16 -1 (2925 3650)(2925 3700);
WIRE 16 -1 (2925 3700)(3175 3700);
WIRE 16 -1 (2925 3700)(2925 3750);
WIRE 16 -1 (2925 3750)(3175 3750);
WIRE 16 -1 (2925 3750)(2925 3800);
WIRE 16 -1 (2925 3800)(3175 3800);
WIRE 16 -1 (2925 3800)(2925 3850);
WIRE 16 -1 (2925 3850)(3175 3850);
WIRE 16 -1 (2925 3850)(2925 3900);
WIRE 16 -1 (2925 3900)(3175 3900);
WIRE 16 -1 (2925 3900)(2925 3950);
WIRE 16 -1 (2925 3950)(3175 3950);
WIRE 16 -1 (2925 3950)(2925 4000);
WIRE 16 -1 (2925 4000)(3175 4000);
WIRE 16 -1 (2925 4000)(2925 4050);
WIRE 16 -1 (2925 4050)(3175 4050);
WIRE 16 -1 (2925 4050)(2925 4100);
WIRE 16 -1 (2925 4100)(3175 4100);
WIRE 16 -1 (2925 4100)(2925 4150);
WIRE 16 -1 (3175 4150)(2925 4150);
WIRE 16 -1 (2925 4150)(2925 4200);
WIRE 16 -1 (2925 4200)(3175 4200);
WIRE 16 -1 (2925 4200)(2925 4250);
WIRE 16 -1 (3175 4250)(2925 4250);
WIRE 16 -1 (4375 1100)(4625 1100);
WIRE 16 -1 (4375 1150)(4625 1150);
WIRE 16 -1 (4625 1150)(4625 1100);
WIRE 16 -1 (4375 1250)(4625 1250);
WIRE 16 -1 (4625 1250)(4625 1150);
WIRE 16 -1 (4375 1300)(4625 1300);
WIRE 16 -1 (4625 1300)(4625 1250);
WIRE 16 -1 (4375 1350)(4625 1350);
WIRE 16 -1 (4625 1300)(4625 1350);
WIRE 16 -1 (4375 1400)(4625 1400);
WIRE 16 -1 (4625 1400)(4625 1350);
WIRE 16 -1 (4375 1450)(4625 1450);
WIRE 16 -1 (4625 1450)(4625 1400);
WIRE 16 -1 (4375 1500)(4625 1500);
WIRE 16 -1 (4625 1500)(4625 1450);
WIRE 16 -1 (4375 1550)(4625 1550);
WIRE 16 -1 (4625 1550)(4625 1500);
WIRE 16 -1 (4375 1600)(4625 1600);
WIRE 16 -1 (4625 1600)(4625 1550);
WIRE 16 -1 (4375 1650)(4625 1650);
WIRE 16 -1 (4625 1650)(4625 1600);
WIRE 16 -1 (4625 1700)(4375 1700);
WIRE 16 -1 (4625 1700)(4625 1650);
WIRE 16 -1 (4625 1750)(4375 1750);
WIRE 16 -1 (4625 1750)(4625 1700);
WIRE 16 -1 (4625 1800)(4375 1800);
WIRE 16 -1 (4625 1800)(4625 1750);
WIRE 16 -1 (4375 1850)(4625 1850);
WIRE 16 -1 (4625 1800)(4625 1850);
WIRE 16 -1 (4625 1900)(4375 1900);
WIRE 16 -1 (4625 1850)(4625 1900);
WIRE 16 -1 (4625 1950)(4375 1950);
WIRE 16 -1 (4625 1950)(4625 1900);
WIRE 16 -1 (4625 2000)(4375 2000);
WIRE 16 -1 (4625 2000)(4625 1950);
WIRE 16 -1 (4625 2050)(4625 2000);
WIRE 16 -1 (4625 2050)(4375 2050);
WIRE 16 -1 (4375 2100)(4625 2100);
WIRE 16 -1 (4625 2100)(4625 2050);
WIRE 16 -1 (4375 2150)(4625 2150);
WIRE 16 -1 (4625 2150)(4625 2100);
WIRE 16 -1 (4375 2200)(4625 2200);
WIRE 16 -1 (4625 2150)(4625 2200);
WIRE 16 -1 (4375 2250)(4625 2250);
WIRE 16 -1 (4625 2250)(4625 2200);
WIRE 16 -1 (4375 2300)(4625 2300);
WIRE 16 -1 (4625 2300)(4625 2250);
WIRE 16 -1 (4375 2350)(4625 2350);
WIRE 16 -1 (4625 2350)(4625 2300);
WIRE 16 -1 (4375 2400)(4625 2400);
WIRE 16 -1 (4625 2400)(4625 2350);
WIRE 16 -1 (4375 2450)(4625 2450);
WIRE 16 -1 (4625 2450)(4625 2400);
WIRE 16 -1 (4625 2500)(4375 2500);
WIRE 16 -1 (4625 2500)(4625 2450);
WIRE 16 -1 (4625 2550)(4375 2550);
WIRE 16 -1 (4625 2550)(4625 2500);
WIRE 16 -1 (4375 2600)(4625 2600);
WIRE 16 -1 (4625 2600)(4625 2550);
WIRE 16 -1 (4375 2650)(4625 2650);
WIRE 16 -1 (4625 2650)(4625 2600);
WIRE 16 -1 (4375 2700)(4625 2700);
WIRE 16 -1 (4625 2650)(4625 2700);
WIRE 16 -1 (4375 2750)(4625 2750);
WIRE 16 -1 (4625 2750)(4625 2700);
WIRE 16 -1 (4375 2800)(4625 2800);
WIRE 16 -1 (4625 2800)(4625 2750);
WIRE 16 -1 (4375 2850)(4625 2850);
WIRE 16 -1 (4625 2850)(4625 2800);
WIRE 16 -1 (4375 2900)(4625 2900);
WIRE 16 -1 (4625 2900)(4625 2850);
WIRE 16 -1 (4375 2950)(4625 2950);
WIRE 16 -1 (4625 2950)(4625 2900);
WIRE 16 -1 (4625 3000)(4375 3000);
WIRE 16 -1 (4625 3000)(4625 2950);
WIRE 16 -1 (4625 3050)(4375 3050);
WIRE 16 -1 (4625 3050)(4625 3000);
WIRE 16 -1 (4625 3100)(4625 3050);
WIRE 16 -1 (4375 3100)(4625 3100);
WIRE 16 -1 (4375 3150)(4625 3150);
WIRE 16 -1 (4625 3150)(4625 3100);
WIRE 16 -1 (4375 3200)(4625 3200);
WIRE 16 -1 (4625 3150)(4625 3200);
WIRE 16 -1 (4375 3250)(4625 3250);
WIRE 16 -1 (4625 3250)(4625 3200);
WIRE 16 -1 (4375 3300)(4625 3300);
WIRE 16 -1 (4625 3300)(4625 3250);
WIRE 16 -1 (4375 3350)(4625 3350);
WIRE 16 -1 (4625 3350)(4625 3300);
WIRE 16 -1 (4375 3400)(4625 3400);
WIRE 16 -1 (4625 3400)(4625 3350);
WIRE 16 -1 (4375 3450)(4625 3450);
WIRE 16 -1 (4625 3450)(4625 3400);
WIRE 16 -1 (4625 3500)(4375 3500);
WIRE 16 -1 (4625 3500)(4625 3450);
WIRE 16 -1 (4625 3550)(4375 3550);
WIRE 16 -1 (4625 3550)(4625 3500);
WIRE 16 -1 (4375 3600)(4625 3600);
WIRE 16 -1 (4625 3600)(4625 3550);
WIRE 16 -1 (4375 3650)(4625 3650);
WIRE 16 -1 (4625 3650)(4625 3600);
WIRE 16 -1 (4375 3700)(4625 3700);
WIRE 16 -1 (4625 3650)(4625 3700);
WIRE 16 -1 (4375 3750)(4625 3750);
WIRE 16 -1 (4625 3750)(4625 3700);
WIRE 16 -1 (4375 3800)(4625 3800);
WIRE 16 -1 (4625 3800)(4625 3750);
WIRE 16 -1 (4375 3850)(4625 3850);
WIRE 16 -1 (4625 3850)(4625 3800);
WIRE 16 -1 (4375 3900)(4625 3900);
WIRE 16 -1 (4625 3900)(4625 3850);
WIRE 16 -1 (4375 3950)(4625 3950);
WIRE 16 -1 (4625 3950)(4625 3900);
WIRE 16 -1 (4375 4000)(4625 4000);
WIRE 16 -1 (4625 4000)(4625 3950);
WIRE 16 -1 (4375 4050)(4625 4050);
WIRE 16 -1 (4625 4050)(4625 4000);
WIRE 16 -1 (4625 4100)(4625 4050);
WIRE 16 -1 (4375 4100)(4625 4100);
WIRE 16 -1 (4375 4150)(4625 4150);
WIRE 16 -1 (4625 4150)(4625 4100);
WIRE 16 -1 (4375 4200)(4625 4200);
WIRE 16 -1 (4625 4200)(4625 4150);
WIRE 16 -1 (4375 4250)(4625 4250);
WIRE 16 -1 (4625 4250)(4625 4200);
WIRE 16 -1 (4375 4300)(4625 4300);
WIRE 16 -1 (4625 4300)(4625 4250);
WIRE 16 -1 (4375 4350)(4625 4350);
WIRE 16 -1 (4625 4350)(4625 4300);
WIRE 16 -1 (4625 4400)(4625 4350);
WIRE 16 -1 (4375 4400)(4625 4400);
WIRE 16 -1 (-2925 3550)(-4025 3550);
FORCEPROP 2 LAST SIG_NAME M_G_CPU1_SB_PAR
J 0
(-3937 3559);
DISPLAY 0.680851 (-3937 3559);
PAINT WHITE (-3937 3559);
WIRE 16 -1 (-2925 3600)(-4025 3600);
FORCEPROP 2 LAST SIG_NAME M_G_CPU1_SA_PAR
J 0
(-3937 3609);
DISPLAY 0.680851 (-3937 3609);
PAINT WHITE (-3937 3609);
WIRE 16 -1 (-1725 3750)(-1550 3750);
WIRE 16 -1 (-1725 3900)(-1550 3900);
WIRE 16 -1 (-1725 4050)(-1550 4050);
WIRE 16 -1 (-3100 2850)(-2925 2850);
WIRE 16 -1 (-3100 2800)(-2925 2800);
WIRE 16 -1 (-1725 2050)(-1550 2050);
WIRE 16 -1 (-2925 1150)(-4025 1150);
FORCEPROP 2 LAST SIG_NAME TP_CHG_CPU1_DIMM2_FRU_0
J 0
(-3937 1159);
DISPLAY 0.680851 (-3937 1159);
PAINT WHITE (-3937 1159);
WIRE 16 -1 (-2925 1200)(-4025 1200);
FORCEPROP 2 LAST SIG_NAME TP_CHG_CPU1_DIMM2_FRU_1
J 0
(-3937 1209);
DISPLAY 0.680851 (-3937 1209);
PAINT WHITE (-3937 1209);
WIRE 16 -1 (-2925 1250)(-4025 1250);
FORCEPROP 2 LAST SIG_NAME TP_CHG_CPU1_DIMM2_FRU_2
J 0
(-3937 1259);
DISPLAY 0.680851 (-3937 1259);
PAINT WHITE (-3937 1259);
WIRE 16 -1 (-2925 1300)(-4025 1300);
FORCEPROP 2 LAST SIG_NAME TP_CHG_CPU1_DIMM2_FRU_3
J 0
(-3937 1309);
DISPLAY 0.680851 (-3937 1309);
PAINT WHITE (-3937 1309);
WIRE 16 -1 (-2925 1350)(-4025 1350);
FORCEPROP 2 LAST SIG_NAME TP_CHG_CPU1_DIMM2_FRU_4
J 0
(-3937 1359);
DISPLAY 0.680851 (-3937 1359);
PAINT WHITE (-3937 1359);
WIRE 16 -1 (-2925 950)(-4025 950);
FORCEPROP 2 LAST SIG_NAME M_G_CPU1_SB_RSP<1>
J 0
(-3937 959);
DISPLAY 0.680851 (-3937 959);
PAINT WHITE (-3937 959);
WIRE 16 -1 (-2925 1000)(-4025 1000);
FORCEPROP 2 LAST SIG_NAME M_G_CPU1_SA_RSP<1>
J 0
(-3937 1009);
DISPLAY 0.680851 (-3937 1009);
PAINT WHITE (-3937 1009);
WIRE 16 -1 (-1725 1200)(-1550 1200);
WIRE 16 -1 (-1725 1250)(-1550 1250);
WIRE 16 -1 (-1725 1300)(-1550 1300);
WIRE 16 -1 (-1725 1350)(-1550 1350);
WIRE 16 -1 (-1725 1400)(-1550 1400);
WIRE 16 -1 (-1725 1450)(-1550 1450);
WIRE 16 -1 (-1725 1500)(-1550 1500);
WIRE 16 -1 (-1725 1550)(-1550 1550);
WIRE 16 -1 (-1725 1600)(-1550 1600);
WIRE 16 -1 (-1725 1700)(-1550 1700);
WIRE 16 -1 (-1725 1750)(-1550 1750);
WIRE 16 -1 (-1725 1800)(-1550 1800);
WIRE 16 -1 (-1725 1850)(-1550 1850);
WIRE 16 -1 (-1725 1900)(-1550 1900);
WIRE 16 -1 (-1725 1950)(-1550 1950);
WIRE 16 -1 (-1725 2000)(-1550 2000);
WIRE 16 -1 (-1725 2100)(-1550 2100);
WIRE 16 -1 (-1725 2150)(-1550 2150);
WIRE 16 -1 (-1725 2200)(-1550 2200);
WIRE 16 -1 (-1725 2250)(-1550 2250);
WIRE 16 -1 (-1725 2300)(-1550 2300);
WIRE 16 -1 (-1725 2350)(-1550 2350);
WIRE 16 -1 (-1725 2400)(-1550 2400);
WIRE 16 -1 (-1725 2450)(-1550 2450);
WIRE 16 -1 (-1725 2500)(-1550 2500);
WIRE 16 -1 (-1725 2550)(-1550 2550);
WIRE 16 -1 (-1725 2600)(-1550 2600);
WIRE 16 -1 (-1725 2650)(-1550 2650);
WIRE 16 -1 (-1725 2700)(-1550 2700);
WIRE 16 -1 (-1725 2750)(-1550 2750);
WIRE 16 -1 (-1725 2850)(-1550 2850);
WIRE 16 -1 (-1725 2900)(-1550 2900);
WIRE 16 -1 (-1725 2950)(-1550 2950);
WIRE 16 -1 (-1725 3000)(-1550 3000);
WIRE 16 -1 (-1725 3050)(-1550 3050);
WIRE 16 -1 (-1725 3100)(-1550 3100);
WIRE 16 -1 (-1725 3150)(-1550 3150);
WIRE 16 -1 (-1725 3200)(-1550 3200);
WIRE 16 -1 (-1725 3250)(-1550 3250);
WIRE 16 -1 (-1725 3300)(-1550 3300);
WIRE 16 -1 (-1725 3350)(-1550 3350);
WIRE 16 -1 (-1725 3400)(-1550 3400);
WIRE 16 -1 (-1725 3450)(-1550 3450);
WIRE 16 -1 (-1725 3500)(-1550 3500);
WIRE 16 -1 (-1725 3550)(-1550 3550);
WIRE 16 -1 (-1725 3600)(-1550 3600);
WIRE 16 -1 (-1725 3650)(-1550 3650);
WIRE 16 -1 (-1725 3700)(-1550 3700);
WIRE 16 -1 (-1725 3800)(-1550 3800);
WIRE 16 -1 (-1725 3850)(-1550 3850);
WIRE 16 -1 (-1725 3950)(-1550 3950);
WIRE 16 -1 (-1725 4000)(-1550 4000);
WIRE 16 -1 (-1725 4100)(-1550 4100);
WIRE 16 -1 (-1725 4150)(-1550 4150);
WIRE 16 -1 (-1725 4200)(-1550 4200);
WIRE 16 -1 (-1725 4250)(-1550 4250);
WIRE 16 -1 (-1725 4300)(-1550 4300);
WIRE 16 -1 (-1725 4350)(-1550 4350);
WIRE 16 -1 (-2925 3300)(-4025 3300);
FORCEPROP 2 LAST SIG_NAME M_G_CPU1_SB_CS_N<3>
J 0
(-3937 3309);
DISPLAY 0.680851 (-3937 3309);
PAINT WHITE (-3937 3309);
WIRE 16 -1 (-2925 3450)(-4025 3450);
FORCEPROP 2 LAST SIG_NAME M_G_CPU1_SA_CS_N<3>
J 0
(-3937 3459);
DISPLAY 0.680851 (-3937 3459);
PAINT WHITE (-3937 3459);
WIRE 16 -1 (-2925 3250)(-4025 3250);
FORCEPROP 2 LAST SIG_NAME M_G_CPU1_SB_CS_N<2>
J 0
(-3937 3259);
DISPLAY 0.680851 (-3937 3259);
PAINT WHITE (-3937 3259);
WIRE 16 -1 (-2925 3400)(-4025 3400);
FORCEPROP 2 LAST SIG_NAME M_G_CPU1_SA_CS_N<2>
J 0
(-3937 3409);
DISPLAY 0.680851 (-3937 3409);
PAINT WHITE (-3937 3409);
WIRE 16 -1 (-2925 3150)(-4025 3150);
FORCEPROP 2 LAST SIG_NAME M_G_CPU1_CLK_DP<1>
J 0
(-3937 3159);
DISPLAY 0.680851 (-3937 3159);
PAINT WHITE (-3937 3159);
WIRE 16 -1 (-2925 3100)(-4025 3100);
FORCEPROP 2 LAST SIG_NAME M_G_CPU1_CLK_DN<1>
J 0
(-3937 3109);
DISPLAY 0.680851 (-3937 3109);
PAINT WHITE (-3937 3109);
WIRE 16 -1 (-3100 2200)(-2925 2200);
WIRE 16 -1 (-3100 2250)(-2925 2250);
WIRE 16 -1 (-3100 2300)(-2925 2300);
WIRE 16 -1 (-3100 2350)(-2925 2350);
WIRE 16 -1 (-3100 2400)(-2925 2400);
WIRE 16 -1 (-3100 2450)(-2925 2450);
WIRE 16 -1 (-3100 2500)(-2925 2500);
WIRE 16 -1 (-3100 2650)(-2925 2650);
WIRE 16 -1 (-3100 2750)(-2925 2750);
WIRE 16 -1 (-3100 2900)(-2925 2900);
WIRE 16 -1 (-3100 2950)(-2925 2950);
WIRE 16 -1 (-3100 4000)(-2925 4000);
WIRE 16 -1 (-3100 4400)(-2925 4400);
WIRE 16 -1 (-3100 3950)(-2925 3950);
WIRE 16 -1 (-3100 4350)(-2925 4350);
WIRE 16 -1 (-3100 3900)(-2925 3900);
WIRE 16 -1 (-3100 4300)(-2925 4300);
WIRE 16 -1 (-3100 3850)(-2925 3850);
WIRE 16 -1 (-3100 4250)(-2925 4250);
WIRE 16 -1 (-3100 3800)(-2925 3800);
WIRE 16 -1 (-3100 4200)(-2925 4200);
WIRE 16 -1 (-3100 3750)(-2925 3750);
WIRE 16 -1 (-3100 4150)(-2925 4150);
WIRE 16 -1 (-3100 3700)(-2925 3700);
WIRE 16 -1 (-3100 4100)(-2925 4100);
WIRE 16 -1 (-3100 2550)(-2925 2550);
WIRE 16 -1 (-3100 2700)(-2925 2700);
WIRE 16 -1 (-3100 3000)(-2925 3000);
WIRE 16 -1 (-1725 4400)(-1550 4400);
WIRE 16 -1 (-2925 450)(-4025 450);
FORCEPROP 2 LAST SIG_NAME PD_CHG_CPU1_DIMM2_SAA
J 0
(-3937 459);
DISPLAY 0.680851 (-3937 459);
PAINT WHITE (-3937 459);
WIRE 16 -1 (-2925 350)(-2925 450);
DOT 1 (4625 1050);
DOT 1 (4625 1100);
DOT 1 (4625 1150);
DOT 1 (4625 4350);
DOT 1 (4625 4300);
DOT 1 (4625 4250);
DOT 1 (4625 4200);
DOT 1 (4625 4150);
DOT 1 (4625 4100);
DOT 1 (4625 4050);
DOT 1 (4625 4000);
DOT 1 (4625 3950);
DOT 1 (4625 3900);
DOT 1 (4625 3850);
DOT 1 (4625 3800);
DOT 1 (4625 3750);
DOT 1 (4625 3700);
DOT 1 (4625 3650);
DOT 1 (4625 3600);
DOT 1 (4625 3550);
DOT 1 (4625 3500);
DOT 1 (4625 3450);
DOT 1 (4625 3400);
DOT 1 (4625 3350);
DOT 1 (4625 3300);
DOT 1 (4625 3250);
DOT 1 (4625 3200);
DOT 1 (4625 3150);
DOT 1 (4625 3100);
DOT 1 (4625 3050);
DOT 1 (4625 3000);
DOT 1 (4625 2950);
DOT 1 (4625 2900);
DOT 1 (4625 2850);
DOT 1 (4625 2800);
DOT 1 (4625 2750);
DOT 1 (4625 2700);
DOT 1 (4625 2600);
DOT 1 (4625 2650);
DOT 1 (4625 2550);
DOT 1 (4625 2500);
DOT 1 (4625 2450);
DOT 1 (4625 2400);
DOT 1 (4625 2350);
DOT 1 (4625 2300);
DOT 1 (4625 2250);
DOT 1 (4625 2200);
DOT 1 (4625 2150);
DOT 1 (4625 2100);
DOT 1 (4625 2050);
DOT 1 (4625 2000);
DOT 1 (4625 1950);
DOT 1 (4625 1900);
DOT 1 (4625 1850);
DOT 1 (4625 1800);
DOT 1 (4625 1750);
DOT 1 (4625 1700);
DOT 1 (4625 1650);
DOT 1 (4625 1600);
DOT 1 (4625 1550);
DOT 1 (4625 1500);
DOT 1 (4625 1450);
DOT 1 (4625 1400);
DOT 1 (4625 1350);
DOT 1 (4625 1300);
DOT 1 (4625 1250);
DOT 1 (2925 4400);
DOT 1 (2925 4350);
DOT 1 (2925 4200);
DOT 1 (2925 4150);
DOT 1 (2925 4100);
DOT 1 (2925 4050);
DOT 1 (2925 4000);
DOT 1 (2925 3950);
DOT 1 (2925 3900);
DOT 1 (2925 3850);
DOT 1 (2925 3800);
DOT 1 (2925 3750);
DOT 1 (2925 3700);
DOT 1 (2925 3650);
DOT 1 (2925 3600);
DOT 1 (2925 3500);
DOT 1 (2925 3450);
DOT 1 (2925 3400);
DOT 1 (2925 3350);
DOT 1 (2925 3300);
DOT 1 (2925 3250);
DOT 1 (2925 3200);
DOT 1 (2925 3100);
DOT 1 (2925 3150);
DOT 1 (2925 3050);
DOT 1 (2925 3000);
DOT 1 (2925 2850);
DOT 1 (2925 2800);
DOT 1 (2925 2750);
DOT 1 (2925 2700);
DOT 1 (2925 2650);
DOT 1 (2925 2550);
DOT 1 (2925 2500);
DOT 1 (2925 2450);
DOT 1 (2925 2400);
DOT 1 (2925 2350);
DOT 1 (2925 2300);
DOT 1 (2925 2250);
DOT 1 (2925 2200);
DOT 1 (2925 2150);
DOT 1 (2925 2100);
DOT 1 (2925 2050);
DOT 1 (2925 2000);
DOT 1 (2925 1950);
DOT 1 (2925 1900);
DOT 1 (2925 1850);
DOT 1 (2925 1800);
DOT 1 (2925 1750);
DOT 1 (2925 1700);
DOT 1 (2925 1650);
DOT 1 (2925 1550);
DOT 1 (2925 1500);
DOT 1 (2925 1450);
DOT 1 (2925 1400);
DOT 1 (2925 1350);
DOT 1 (2925 1300);
DOT 1 (2925 1250);
DOT 1 (2925 1200);
DOT 1 (2925 1150);
DOT 1 (1850 275);
DOT 1 (1225 750);
DOT 1 (2925 3550);
DOT 1 (2925 2900);
DOT 1 (2925 2950);
DOT 1 (2925 2600);
DOT 1 (2925 1600);
FORCENOTE
20210728 MODIFY FOR GT
(-4425 5075) 0;
DISPLAY LEFT (-4425 5075);
DISPLAY 2.510638 (-4425 5075);
PAINT PINK (-4425 5075);
QUIT
